# HONEY BADGER LSI BASEBOARD HS(D)-1B BOM of 55.B0710.D12G_20150213.xlsx — HONEY BADGER LSI BASEBOARD HS(D (bom)
| Level | Parent Number | Part Number | Description | Green Factor | Life Cycle State | Manufacturer | Manufacturer Part Number | Source | BOM Usage | M/P Code | S/D | Qty | UoM | Location |
| 1 | 55.B0710.D12G | 022.40001.0541 | SW TACT 4P ST DTS-63N-V ,PA66 | R2_SA; | Released | DIPTRONICS | DTS-63N-V | Single |  | Purchase | DIP | 1 | PCS | SW2 |
| 1 | 55.B0710.D12G | 022.70004.0021 | CAGE ASSY 74548-0211 | R2_SA; | Released | MOLEX | 74548-0211 | Single |  | Purchase | DIP | 1 | PCS | CN4 |
| 1 | 55.B0710.D12G | 06.02907.010 | XTOR MPS2907ARLRAG PNP TO-92 | R2_SA; | Released | ON | MPS2907ARLRAG | Single |  | Purchase | DIP | 1 | PCS | Q4 |
| 1 | 55.B0710.D12G | 06.1BETB.14Z | LED RED/BLUE LTL1BETBEK5H149-WN | R2_SA; | Released | LITEON | LTL1BETBEK5H149-WN | Single |  | Purchase | DIP | 1 | PCS | LED7 |
| 1 | 55.B0710.D12G | 20.50409.164 | CONN EDGE 164P AAA-PCI-006-G05 ,PA46 | R2_SA; | Released | LOTES | AAA-PCI-006-G05 | Single |  | Purchase | DIP | 1 | PCS | CN8 |
| 1 | 55.B0710.D12G | 21.61359.104 | HEAD ML 1R4P ST D2.54 A2541WV0-1QX4PA-6T | R2_SA; | Released | JWT | A2541WV0-1Qx4PA-6T | Single |  | Purchase | DIP | 2 | PCS | SCN5 SCN8 |
| 1 | 55.B0710.D12G | 21.63105.207 | HEAD ML RT 2R14P A2005WR0-2CX7P-6T | R2_SA; | Released | JWT | A2005WR0-2Cx7P-6T | Single |  | Purchase | DIP | 1 | PCS | CN3 |
| 1 | 55.B0710.D12G | 21.65007.102 | HEAD ML 1R2P 68001-202HLF ,PCT | R2_SA; | Released | FCI | 68001-202HLF | Single |  | Purchase | DIP | 1 | PCS | JP1 |
| 1 | 55.B0710.D12G | 22.10254.181 | SKT USB CONN 4P RT 67643-3911 | R2_SA;G_SA; | Released | MOLEX | 67643-3911 | Single |  | Purchase | DIP | 1 | PCS | SKT1 |
| 1 | 55.B0710.D12G | 22.40069.J01 | SW TACT 4P DTS-65R-Q | R2_SA; | Released | DIPTRONICS | DTS-65R-Q | Single |  | Purchase | DIP | 1 | PCS | SW1 |
| 1 | 55.B0710.D12G | 22.70034.181 | HOLDER BTY 2032 AAA-BAT-043-K01 ,PA66 | R2_SA; | Released | LOTES | AAA-BAT-043-K01 | Single |  | Purchase | DIP | 1 | PCS | BAT1 |
| 1 | 55.B0710.D12G | 23.20068.001 | BTY RTC CR2032 KTS | R2_SA;HF_SA; | Released | KTS | BBBCR2032BX | Single |  | Purchase | DIP | 1 | PCS | BAT1 |
| 1 | 55.B0710.D12G | 34.B0701.001 | ASSY HSINK_68X25X30_PUSH PIN_PAD_HB | R2_SA; | Released | CCI | Void | Single |  | Purchase | DIP | 1 | PCS | SU1 |
| 1 | 55.B0710.D12G | 34.B0706.001 | HSINK_31X48X30_PUSH PIN_PAD_HB | R2_SA; | Released | CCI | CCI | Single |  | Purchase | DIP | 1 | PCS | SU2 |
| 1 | 55.B0710.D12G | 42.B0716.001 | SPACER THERMAL H5 HU230H | R2_C; | Released | TBD |  | Single |  | Purchase | DIP | 1 | PCS | Q4 |
| 1 | 55.B0710.D12G | 42.B0717.001 | CVR PANTHER PLUS HB | R2_C; | Released | TBD |  | Single |  | Purchase | DIP | 1 | PCS |  |
| 1 | 55.B0710.D12G | 42.B0719.001 | SPACER 10G CARD LATCH HB GREEN | R2_C; | Released | TBD |  | Single |  | Purchase | DIP | 2 | PCS |  |
| 1 | 55.B0710.D12G | 42.B0720.001 | SPACER 10G CARD HB GREEN | R2_C; | Released | TBD |  | Single |  | Purchase | DIP | 2 | PCS |  |
| 1 | 55.B0710.D12G | 55.B0710.S12G | HONEY BADGER LSI BASEBOARD HS(S)-1B | N/A; | Released |  |  |  | E | Manufacture | DIP | 1 | PCS |  |
| 2 | 55.B0710.S12G | 074.01278.0A7Z | IC SWAP CTRL ADM1278-2ACPZ-RL LFCSP 32P | R2_SA; | Released | ADI | ADM1278-2ACPZ-RL | Single |  | Purchase | SMT | 1 | PCS | U2 |
| 2 | 55.B0710.S12G | 075.09904.0A7C | IC DIOSE ESD PROT AZC099-04S SOT23-6L | R2_C; | Released | AMAZING | AZC099-04S | Single |  | Purchase | SMT | 1 | PCS | U22 |
| 2 | 55.B0710.S12G | 078.47522.0211 | CHIP CAP C 4.7U 25V K0805 X7R | R2_SA;HF_SA;G_SA; | Released | WALSIN;SAMSUNG;MURATA | 0805B475K250CT;CL21B475KAFNNNE;GRM21BR71E475KA73L | Multiple |  | Purchase | SMT | 3 | PCS | PC184 PC26 PC46 |
| 2 | 55.B0710.S12G | 19-000386$AB | IC CTRL SAS3X24RLC1-DB-500021106 FPBGA | R2_C; | Released | LSI | 500021106 | Single |  | Purchase | SMT | 1 | PCS | SU1 |
| 2 | 55.B0710.S12G | 19-000387$AA | IC CTRL SAS3008C0-1-DB-500020657 FPBGA | R2_C; | Released | LSI | 500020657 | Single |  | Purchase | SMT | 1 | PCS | SU2 |
| 2 | 55.B0710.S12G | 20.F0977.026 | CONN CTR 26P 75586-0009 SMD ,LCP | R2_SA;G_SA; | Released | MOLEX | 75586-0009 | Single |  | Purchase | SMT | 1 | PCS | CN1 |
| 2 | 55.B0710.S12G | 20.F0986.036 | CONN CTR SMD 36P G40MR36U11AEU ,LCP | R2_SA; | Released | AMPHENOL | G40MR36U11AEU | Single |  | Purchase | SMT | 1 | PCS | CN2 |
| 2 | 55.B0710.S12G | 20.F1354.120 | CONN CTR SMD 120P 61082-121402LF ,LCP | R2_SA; | Released | FCI | 61082-121402LF | Single |  | Purchase | SMT | 1 | PCS | MEZCN1 |
| 2 | 55.B0710.S12G | 48.B0734.01B | PCB 13948-1B HONEY BADGER BASEBOARD 8L H | R2_C; | Released | HANNSTAR |  | Single |  | Purchase | SMT | 1 | PCS |  |
| 2 | 55.B0710.S12G | 62.10089.021 | SKT SPI CONN ACA-SPI-006-K01 ,LCP | R2_SA;HF_SA; | Released | LOTES | ACA-SPI-006-K01 | Single |  | Purchase | SMT | 1 | PCS | SKT3 |
| 2 | 55.B0710.S12G | 62.40007.231 | SW PUSH 5P PTCFGP2-Q-TR SMD | R2_SA; | Released | DIPTRONICS | PTCFGP2-Q-TR | Single |  | Purchase | SMT | 1 | PCS | SW3 |
| 2 | 55.B0710.S12G | 62.40018.451 | SW SLIDE 3P LSSM12-P-V-TR SMD | R2_SA; | Released | DIPTRONICS | LSSM12-P-V-TR | Single |  | Purchase | SMT | 1 | PCS | SW20 |
| 2 | 55.B0710.S12G | 63.00000.00L | CHIP RES 0 J 1/10W 0603 | R2_SA;HF_SA;G_SA; | Released | TA-I ; RALEC ; YAGEO ; WALSIN | RM06JTN0 ; RTT03000JTP ; RC0603JR-070RL ; WR06X000PTL | Multiple |  | Purchase | SMT | 8 | PCS | PR150 R446 R545 R551 R554 R556 R557 SR807 |
| 2 | 55.B0710.S12G | 63.10034.1DL | CHIP RES 10 J 1/16W 0402 | R2_SA;HF_SA;G_SA; | Released | TA-I ; RALEC ; CYNTEC ; YAGEO;WALSIN | RM04JTN100 ; RTT02100JTH ; RR0510S-100-JN ; RC0402JR-0710RL;WR04X100JTL | Multiple |  | Purchase | SMT | 1 | PCS | R2111 |
| 2 | 55.B0710.S12G | 63.10234.1DL | CHIP RES 1K J 1/16W 0402 | R2_SA;HF_SA;G_SA; | Released | TA-I;RALEC;CYNTEC;YAGEO;WALSIN | RM04JTN102 ; RTT02102JTH ; RR0510S-102-JN ; RC0402JR-071KL;WR04X102JTL | Multiple |  | Purchase | SMT | 10 | PCS | PR171 R2110 R5202 R576 R600 R604 SR1272 SR1276 SR856 SR860 |
| 2 | 55.B0710.S12G | 63.10434.L1L | CHIP RES 100K J 1/16W 0402 13" REEL | R2_SA;HF_SA;G_SA; | Released | YAGEO;RALEC;WALSIN;TAI | RC0402JR-13100KL;RTT02104JH5;WR04X104 JHL;RM04JLN104 | Multiple |  | Purchase | SMT | 3 | PCS | R2117 R2171 R2174 |
| 2 | 55.B0710.S12G | 63.12334.1DL | CHIP RES 12K J 1/16W 0402 | R2_SA;HF_SA;G_SA; | Released | TA-I ; RALEC ; CYNTEC ; YAGEO | RM04JTN123 ; RTT02123JTH ; RR0510S-123-JN ; RC0402JR-0712KL | Multiple |  | Purchase | SMT | 1 | PCS | R700 |
| 2 | 55.B0710.S12G | 63.15133.15L | CHIP RES 150 J 1/10W 0603 | R2_SA;HF_SA;G_SA; | Released | TA-I ; RALEC ; YAGEO | RM06JTN151 ; RTT03151JTP ; RC0603JR-07150RL | Multiple |  | Purchase | SMT | 2 | PCS | R415 R420 |
| 2 | 55.B0710.S12G | 63.15434.1DL | CHIP RES 150K J 1/16W 0402 | R2_SA;HF_SA;G_SA; | Released | TA-I ; RALEC ; CYNTEC;YAGEO | RM04JTN154 ; RTT02154JTH ; RR-0510S-154-JN ; RC0402JR-07150KL | Multiple |  | Purchase | SMT | 1 | PCS | R2103 |
| 2 | 55.B0710.S12G | 63.18232.11L | CHIP RES 1.8K J 1/4W 1206 | R2_SA;HF_SA;G_SA; | Released | RALEC ; TA-I ; YAGEO | RTT06182JTP ; RM12JTN182 ; RC1206JR-071K8L | Multiple |  | Purchase | SMT | 1 | PCS | R659 |
| 2 | 55.B0710.S12G | 63.22234.1DL | CHIP RES 2.2K J 1/16W 0402 | R2_SA;HF_SA;G_SA; | Released | TA-I;RALEC;CYNTEC;YAGEO;WALSIN | RM04JTN222 ; RTT02222JTH ; RR0510S-222-JN ; RC0402JR-072K2L;WR04X222JTL | Multiple |  | Purchase | SMT | 4 | PCS | R264 R266 R421 R486 |
| 2 | 55.B0710.S12G | 63.27234.1DL | CHIP RES 2.7K J 1/16W 0402 | R2_SA;HF_SA;G_SA; | Released | TA-I ; RALEC ; CYNTEC;YAGEO | RM04JTN272 ; RTT02272JTH ; RR-0510S-272-JN ; RC0402JR-072K7L | Multiple |  | Purchase | SMT | 2 | PCS | PR125 PR82 |
| 2 | 55.B0710.S12G | 63.2R233.15L | CHIP RES 2.2 J 1/10W 0603 | R2_SA;HF_SA;G_SA; | Released | TA-I ; RALEC ; YAGEO ; WALSIN | RM06JTN2R2 ; RTT032R2JTP ; RC0603JR-072R2L ; WR06X2R2JTL | Multiple |  | Purchase | SMT | 4 | PCS | PR19 PR39 PR4 PR9008 |
| 2 | 55.B0710.S12G | 63.30234.1DL | CHIP RES 3K J 1/16W 0402(ROHS) | R2_SA;HF_SA;G_SA; | Released | TA-I;RALEC;CYNTEC;YAGEO;WALSIN | RM04JTN302 ; RTT02302JTH ; RR0510S-302-JN ; RC0402JR-073KL;WR04X302JTL | Multiple |  | Purchase | SMT | 2 | PCS | SR650 SR757 |
| 2 | 55.B0710.S12G | 63.33034.1DL | CHIP RES 33 J 1/16W 0402 | R2_SA;HF_SA;G_SA; | Released | TA-I;RALEC;CYNTEC;YAGEO;WALSIN | RM04JTN330 ; RTT02330JTH ; RR0510S-330-JN ; RC0402JR-0733RL;WR04X330JTL | Multiple |  | Purchase | SMT | 5 | PCS | R375 R376 R379 R458 R528 |
| 2 | 55.B0710.S12G | 63.33137.1BL | CHIP RES 330 J 1/2W 1210 | R2_SA;HF_SA;G_SA; | Released | YAGEO | RC1210JR-07330RL | Single |  | Purchase | SMT | 2 | PCS | R543 R5774 |
| 2 | 55.B0710.S12G | 63.47234.1DL | CHIP RES 4.7K J 1/16W 0402 | R2_SA;HF_SA;G_SA; | Released | TA-I;RALEC;CYNTEC;YAGEO;WALSIN | RM04JTN472 ; RTT02472JTH ; RR0510S-472-JN ; RC0402JR-074K7L;WR04X472JTL | Multiple |  | Purchase | SMT | 1 | PCS | R172 |
| 2 | 55.B0710.S12G | 63.82234.1DL | CHIP RES 8.2K J 1/16W 0402 | R2_SA;HF_SA;G_SA; | Released | TA-I;RALEC;CYNTEC;YAGEO;WALSIN | RM04JTN822 ; RTT02822JTH ; RR0510S-822-JN ; RC0402JR-078K2L;WR04X822JTL | Multiple |  | Purchase | SMT | 6 | PCS | R197 R198 R199 R200 R317 R453 |
| 2 | 55.B0710.S12G | 63.R0031.16L | CHIP RES 0 J 1/8W 0805 | R2_SA;HF_SA;G_SA; | Released | TA-I ; RALEC ; YAGEO ; WALSIN | RM10JTN0 ; RTT05000JTP ; RC0805JR-070RL ; WR08X000PTL | Multiple |  | Purchase | SMT | 2 | PCS | PR153 SR870 |
| 2 | 55.B0710.S12G | 63.R0032.11L | CHIP RES 0 J 1/4W 1206 (ROHS) | R2_SA;HF_SA;G_SA; | Released | TA-I ; RALEC ; YAGEO; WALSIN | RM12JTN0 ; RTT06000JTP ; RC1206JR-070RL; WR12X000 PTL | Multiple |  | Purchase | SMT | 7 | PCS | PR120 PR5 PR77 PR78 PR84 PR85 PR9009 |
| 2 | 55.B0710.S12G | 63.R0034.1DL | CHIP RES 0 J 1/16W 0402 | R2_SA;HF_SA;G_SA; | Released | TA-I;RALEC;CYNTEC;YAGEO;WALSIN | RM04JTN0;RTT02000JTH;RR0510X-000-XN;RC0402JR-070RL;WR04X000PTL | Multiple |  | Purchase | SMT | 293 | PCS | PR11 PR117 PR12 PR124 PR126 PR152 PR169 PR172 PR176 PR178 PR192 PR21 PR22 PR36 PR40 PR56 PR58 PR81 PR83 PR88 PR90 PR9000 PR9001 PR9004 PR9006 PR9015 PR9016 PR9020 R125 R148 R149 R150 R151 R152 R153 R154 R155 R156 R157 R158 R1583 R1587 R159 R162 R168 R169 R179 R180 R181 R182 R183 R184 R19 R190 R191 R204 R205 R206 R207 R208 R209 R210 R211 R2114 R212 R213 R214 R215 R2172 R218 R220 R224 R225 R238 R239 R240 R241 R242 R243 R244 R245 R246 R247 R249 R250 R251 R252 R253 R270 R271 R272 R273 R275 R277 R279 R280 R281 R282 R283 R284 R285 R286 R287 R292 R299 R302 R303 R304 R305 R308 R312 R313 R315 R316 R318 R319 R320 R321 R322 R323 R328 R329 R330 R331 R332 R372 R373 R380 R381 R385 R386 R388 R389 R409 R410 R412 R413 R414 R435 R449 R450 R454 R460 R461 R462 R465 R466 R467 R468 R469 R470 R471 R474 R476 R482 R487 R491 R499 R5200 R5201 R523 R526 R530 R537 R538 R539 R540 R541 R558 R562 R564 R565 R566 R568 R570 R572 R574 R575 R579 R582 R583 R584 R587 R588 R593 R596 R601 R605 R607 R608 R609 R612 R613 R614 R618 R625 R656 R658 R670 R671 R672 R674 R679 R683 R685 R686 R691 R7889 R7900 R7901 R7902 R7903 R7904 R7905 R7906 R7907 R7908 R805 R806 SR1261 SR1271 SR1273 SR1277 SR262 SR265 SR297 SR298 SR309 SR310 SR311 SR581 SR588 SR597 SR656 SR718 SR722 SR723 SR727 SR728 SR729 SR730 SR764 SR788 SR790 SR792 SR793 SR848 SR850 SR858 SR859 SR861 SR862 SR863 SR864 SR865 SR866 SR867 SR871 SR872 SR875 SR876 SR879 SR880 SR883 SR884 SR887 SR888 SR891 SR892 SR894 SR895 SR898 SR899 SR914 SR922 SR923 SR924 SR925 SR926 SR927 SR928 SR929 SR933 SR934 SR935 SR936 SR937 SR938 SR939 SR940 SR941 SR942 SR957 |
| 2 | 55.B0710.S12G | 64.10005.6DL | CHIP RES 100 F 1/16W 0402 | R2_SA;HF_SA;G_SA; | Released | TA-I ; RALEC ; CYNTEC ; YAGEO;WALSIN | RM04FTN1000 ; RTT021000FTH ; RR0510S-1000-FN ; RC0402FR-07100RL;WR04X1000FTL | Multiple |  | Purchase | SMT | 3 | PCS | R15 R16 R20 |
| 2 | 55.B0710.S12G | 64.10015.6DL | CHIP RES 1K F 1/16W 0402 | R2_SA;HF_SA;G_SA; | Released | TA-I;RALEC;CYNTEC;YAGEO;WALSIN | RM04FTN1001 ; RTT021001FTH ; RR0510S-102-FN ; RC0402FR-071KL;WR04X1001FTL | Multiple |  | Purchase | SMT | 23 | PCS | PR118 PR177 R231 R232 R3029 R433 R484 R485 R500 R501 R524 R532 R544 R5763 R5766 R5768 R5769 R5770 R5771 R5772 R675 R676 SR820 |
| 2 | 55.B0710.S12G | 64.10025.55L | CHIP RES 10K F 1/10W 0603 | R2_SA;HF_SA;G_SA; | Released | TA-I ; RALEC ; YAGEO | RM06FTN1002 ; RTT031002FTP ; RC0603FR-0710KL | Multiple |  | Purchase | SMT | 1 | PCS | R690 |
| 2 | 55.B0710.S12G | 64.10025.6DL | CHIP RES 10K F 1/16W 0402 | R2_SA;HF_SA;G_SA; | Released | TA-I;RALEC;CYNTEC;YAGEO;WALSIN | RM04FTN1002 ; RTT021002FTH ; RR0510S-103-FN ; RC0402FR-0710KL;WR04X1002FTL | Multiple |  | Purchase | SMT | 107 | PCS | PR119 PR13 PR165 PR179 PR184 PR186 PR25 PR37 PR45 PR57 PR6 PR9010 PR9017 R1578 R1584 R21 R219 R22 R221 R257 R260 R261 R262 R263 R268 R269 R301 R306 R307 R309 R310 R324 R335 R399 R400 R407 R424 R426 R428 R430 R440 R441 R443 R447 R448 R472 R475 R480 R492 R519 R521 R525 R546 R563 R573 R577 R622 R624 R627 SR1275 SR1280 SR583 SR584 SR605 SR642 SR649 SR653 SR657 SR659 SR661 SR666 SR667 SR668 SR669 SR681 SR682 SR683 SR684 SR685 SR686 SR687 SR689 SR690 SR691 SR692 SR693 SR694 SR696 SR697 SR699 SR700 SR701 SR702 SR703 SR704 SR705 SR706 SR708 SR732 SR784 SR785 SR794 SR840 SR841 SR855 SR915 SR931 |
| 2 | 55.B0710.S12G | 64.10035.6DL | CHIP RES 100K F 1/16W 0402 | R2_SA;HF_SA;G_SA; | Released | TA-I;RALEC;CYNTEC;YAGEO;WALSIN | RM04FTN1003 ; RTT021003FTH ; RR0510S-104-FN ; RC0402FR-07100KL;WR04X1003FTL | Multiple |  | Purchase | SMT | 15 | PCS | PR168 PR170 PR187 R1227 R170 R171 R230 R233 R234 R235 R236 R237 R258 R259 R327 |
| 2 | 55.B0710.S12G | 64.10045.6DL | CHIP RES 1M F 1/16W 0402 | R2_SA;HF_SA;G_SA; | Released | TA-I;RALEC;CYNTEC;YAGEO;WALSIN | RM04FTN1004;RTT021004FTH;RR0510S-105-FN;RC0402FR-071ML;WR04X1004FTL | Multiple |  | Purchase | SMT | 1 | PCS | R701 |
| 2 | 55.B0710.S12G | 64.10R05.55L | CHIP RES 10 F 1/10W 0603 | R2_SA;HF_SA;G_SA; | Released | TA-I;RALEC;YAGEO;WALSIN | RM06FTN10R0 ; RTT0310R0FTP ; RC0603FR-0710RL;WR06X10R0FTL | Multiple |  | Purchase | SMT | 4 | PCS | PR27 PR47 PR9 PR9013 |
| 2 | 55.B0710.S12G | 64.10R05.6DL | CHIP RES 10 F 1/16W 0402 | R2_SA;HF_SA;G_SA; | Released | TA-I ; RALEC ; CYNTEC ; YAGEO | RM04FTN10R0 ; RTT0210R0FTH ; RR0510S-100-FN ; RC0402FR-0710RL | Multiple |  | Purchase | SMT | 16 | PCS | R2098 R2119 R2122 R298 R522 SR709 SR710 SR711 SR712 SR713 SR714 SR828 SR829 SR830 SR837 SR838 |
| 2 | 55.B0710.S12G | 64.10R75.6DL | CHIP RES 10.7 F 1/16W 0402 | R2_SA;HF_SA;G_SA; | Released | TA-I;RALEC;CYNTEC;YAGEO | RM04FTN10R7 ; RTT0210R7FTH ; RR0510S-10R7-FN ; RC0402FR-0710R7L | Multiple |  | Purchase | SMT | 1 | PCS | PR156 |
| 2 | 55.B0710.S12G | 64.11025.6DL | CHIP RES 11K F 1/16W 0402 | R2_SA;HF_SA;G_SA; | Released | TA-I ; RALEC ; CYNTEC ; YAGEO;WALSIN | RM04FTN1102 ; RTT021102FTH ; RR0510S-1102-FN ; RC0402FR-0711KL;WR04X1102FTL | Multiple |  | Purchase | SMT | 1 | PCS | R1226 |
| 2 | 55.B0710.S12G | 64.11335.6DL | CHIP RES 113K F 1/16W 0402 | R2_SA;HF_SA;G_SA; | Released | TAI;RALEC;CYNTEC;YAGEO;WALSIN | RM04FTN1133;RTT021133FTH;RR0510S-1133-FN;RC0402FR-07113KL;WR04X1133FTL | Multiple |  | Purchase | SMT | 1 | PCS | PR164 |
| 2 | 55.B0710.S12G | 64.12115.6DL | CHIP RES 1.21K F 1/16W 0402 | R2_SA;HF_SA;G_SA; | Released | TA-I;RALEC;CYNTEC;YAGEO;WALSIN | RM04FTN1211;RTT021211FTH;RR0510S-1211-FN;RC0402FR-071K21L;WR04X1211FTL | Multiple |  | Purchase | SMT | 1 | PCS | PR183 |
| 2 | 55.B0710.S12G | 64.1271D.6DL | CHIP RES 1.27K D 1/16W 0402 | R2_SA;HF_SA;G_SA; | Released | RALEC ; CYNTEC ; TA-I ; YAGEO | RTT021271DTH ; RR0510Q-1271-DN ; RM04DTN1271 ; RC0402DR-071K27L | Multiple |  | Purchase | SMT | 1 | PCS | R382 |
| 2 | 55.B0710.S12G | 64.13315.55L | CHIP RES 1.33K F 1/10W 0603 | R2_SA;HF_SA;G_SA; | Released | TA-I ; RALEC ; YAGEO | RM06FTN1331 ; RTT031331FTP ; RC0603FR-071K33L | Multiple |  | Purchase | SMT | 2 | PCS | R527 R692 |
| 2 | 55.B0710.S12G | 64.15005.6DL | CHIP RES 150 F 1/16W 0402 | R2_SA;HF_SA;G_SA; | Released | TAI;RALEC;CYNTEC;YAGEO;WALSIN | RM04FTN1500 ; RTT021500FTH ; RR0510S-1500-FN ; RC0402FR-07150RL;WR04X1500FTL | Multiple |  | Purchase | SMT | 9 | PCS | R378 R395 R396 R85 R86 SR651 SR652 SR707 SR731 |
| 2 | 55.B0710.S12G | 64.15025.6DL | CHIP RES 15K F 1/16W 0402 | R2_SA;HF_SA;G_SA; | Released | TA-I;RALEC;CYNTEC;YAGEO | RM04FTN1502;RTT021502FTH;RR0510S-153-FN;RC0402FR-0715KL | Multiple |  | Purchase | SMT | 1 | PCS | R408 |
| 2 | 55.B0710.S12G | 64.18015.6DL | CHIP RES 1.8K F 1/16W 0402 | R2_SA;HF_SA;G_SA; | Released | TAI;RALEC;CYNTEC;YAGEO | RM04FTN1801;RTT021801FTH;RR0510S-182-FN ;RC0402FR-071K8L | Multiple |  | Purchase | SMT | 1 | PCS | R5765 |
| 2 | 55.B0710.S12G | 64.18735.6DL | CHIP RES 187K F 1/16W 0402 | R2_SA;HF_SA;G_SA; | Released | TA-I ; RALEC ; CYNTEC ; YAGEO ; WALSIN | RM04FTN1873;RTT021873FTH;RR0510S-1873-FN;RC0402FR-07187KL;WR04X1873FTL | Multiple |  | Purchase | SMT | 1 | PCS | PR162 |
| 2 | 55.B0710.S12G | 64.19125.6DL | CHIP RES 19.1K F 1/16W 0402 | R2_SA;HF_SA;G_SA; | Released | TA-I;RALEC;CYNTEC;YAGEO | RM04FTN1912;RTT021912FTH;RR0510S-1912-FN;RC0402FR-0719K1L | Multiple |  | Purchase | SMT | 1 | PCS | PR181 |
| 2 | 55.B0710.S12G | 64.20005.55L | CHIP RES 200 F 1/10W 0603(ROHS | R2_SA;HF_SA;G_SA; | Released | TAI;RALEC;YAGEO | RM06FTN2000;RTT032000FTP;RC0603FR-07200RL | Multiple |  | Purchase | SMT | 2 | PCS | R481 R497 |
| 2 | 55.B0710.S12G | 64.20025.6DL | CHIP RES 20K F 1/16W 0402 | R2_SA;HF_SA;G_SA; | Released | TA-I;RALEC;CYNTEC;YAGEO;WALSIN | RM04FTN2002 ; RTT022002FTH ; RR0510S-203-FN ; RC0402FR-0720KL;WR04X2002FTL | Multiple |  | Purchase | SMT | 3 | PCS | PR116 PR175 PR53 |
| 2 | 55.B0710.S12G | 64.20035.6DL | CHIP RES 200K F 1/16W 0402 | R2_SA;HF_SA;G_SA; | Released | TA-I;RALEC;CYNTEC;YAGEO;WALSIN | RM04FTN2003 ; RTT022003FTH ; RR0510S-204-FN ; RC0402FR-07200KL;WR04X2003FTL | Multiple |  | Purchase | SMT | 7 | PCS | SR580 SR724 SR751 SR754 SR761 SR842 SR919 |
| 2 | 55.B0710.S12G | 64.20045.6DL | CHIP RES 2M F 1/16W 0402 | R2_SA;HF_SA;G_SA; | Released | TA-I;RALEC;CYNTEC;YAGEO | RM04FTN2004;RTT022004FTH;RR0510S-2004-FN;RC0402FR-072ML | Multiple |  | Purchase | SMT | 2 | PCS | R478 R494 |
| 2 | 55.B0710.S12G | 64.20515.6DL | CHIP RES 2.05K F 1/16W 0402 | R2_SA;HF_SA;G_SA; | Released | TA-I;RALEC;CYNTEC;YAGEO | RM04FTN2051;RTT022051FTH;RR0510S-2051-FN;RC0402FR-072K05L | Multiple |  | Purchase | SMT | 1 | PCS | PR6889 |
| 2 | 55.B0710.S12G | 64.22005.6DL | CHIP RES 220 F 1/16W 0402 | R2_SA;HF_SA;G_SA; | Released | TA-I;RALEC;CYNTEC;YAGEO | RM04FTN2200;RTT022200FTH;RR0510S-2200-FN;RC0402FR-07220RL | Multiple |  | Purchase | SMT | 1 | PCS | R531 |
| 2 | 55.B0710.S12G | 64.22015.6DL | CHIP RES 2.2K F 1/16W 0402 | R2_SA;HF_SA;G_SA; | Released | TA-I;RALEC;CYNTEC;YAGEO | RM04FTN2201;RTT022201FTH;RR0510S-222-FN;RC0402FR-072K2L | Multiple |  | Purchase | SMT | 30 | PCS | SR614 SR615 SR616 SR617 SR618 SR619 SR620 SR621 SR622 SR623 SR624 SR625 SR626 SR627 SR628 SR629 SR630 SR631 SR632 SR633 SR735 SR736 SR737 SR738 SR739 SR740 SR741 SR742 SR743 SR744 |
| 2 | 55.B0710.S12G | 64.22025.6DL | CHIP RES 22K F 1/16W 0402 | R2_SA;HF_SA;G_SA; | Released | TAI;RALEC;CYNTEC;YAGEO;WALSIN | RM04FTN2202 ; RTT022202FTH ; RR0510S-223-FN ; RC0402FR-0722KL;WR04X2202FTL | Multiple |  | Purchase | SMT | 1 | PCS | R473 |
| 2 | 55.B0710.S12G | 64.22105.6DL | CHIP RES 221 F 1/16W 0402 | R2_SA;HF_SA;G_SA; | Released | TA-I;RALEC;CYNTEC;YAGEO | RM04FTN2210;RTT022210FTH;RR0510S-2210-FN;RC0402FR-07221RL | Multiple |  | Purchase | SMT | 2 | PCS | PR182 PR191 |
| 2 | 55.B0710.S12G | 64.22115.6DL | CHIP RES 2.21K F 1/16W 0402 | R2_SA;HF_SA;G_SA; | Released | TA-I ; RALEC ; CYNTEC ; YAGEO | RM04FTN2211 ; RTT022211FTH ; RR0510S-2211-FN ; RC0402FR-072K21L | Multiple |  | Purchase | SMT | 1 | PCS | PR155 |
| 2 | 55.B0710.S12G | 64.24005.6DL | CHIP RES 240 F 1/16W 0402(ROHS | R2_SA;HF_SA;G_SA; | Released | TA-I ; RALEC ; CYNTEC ; YAGEO | RM04FTN2400 ; RTT022400FTH ; RR0510S-241-FN ; RC0402FR-07240RL | Multiple |  | Purchase | SMT | 1 | PCS | R229 |
| 2 | 55.B0710.S12G | 64.26125.6DL | CHIP RES 26.1K F 1/16W 0402 | R2_SA;HF_SA;G_SA; | Released | TAI;RALEC;CYNTEC;YAGEO | RM04FTN2612;RTT022612FTH;RR0510S-2612-FN;RC0402FR-0726K1L | Multiple |  | Purchase | SMT | 1 | PCS | R2102 |
| 2 | 55.B0710.S12G | 64.27025.6DL | CHIP RES 27K F 1/16W 0402 | R2_SA;HF_SA;G_SA; | Released | TA-I ; RALEC ; CYNTEC ; YAGEO | RM04FTN2702 ; RTT022702FTH ; RR0510S-273-FN ; RC0402FR-0727KL | Multiple |  | Purchase | SMT | 2 | PCS | R518 R626 |
| 2 | 55.B0710.S12G | 64.27415.55L | CHIP RES 2.74K F 1/10W 0603 | R2_SA;HF_SA;G_SA; | Released | TA-I ; RALEC ; YAGEO | RM06FTN2741 ; RTT032741FTP ; RC0603FR-072K74L | Multiple |  | Purchase | SMT | 1 | PCS | R338 |
| 2 | 55.B0710.S12G | 64.27415.6DL | CHIP RES 2.74K F 1/16W 0402 | R2_SA;HF_SA;G_SA; | Released | TAI;RALEC;CYNTEC;YAGEO | RM04FTN2741;RTT022741FTH;RR0510S-2741-FN;RC0402FR-072K74L | Multiple |  | Purchase | SMT | 1 | PCS | PR86 |
| 2 | 55.B0710.S12G | 64.28705.6DL | CHIP RES 287 F 1/16W 0402 | R2_SA;HF_SA;G_SA; | Released | TA-I;RALEC;CYNTEC;YAGEO | RM04FTN2870;RTT022870FTH;RR0510S-2870-FN;RC0402FR-07287RL | Multiple |  | Purchase | SMT | 1 | PCS | PR194 |
| 2 | 55.B0710.S12G | 64.30005.55L | CHIP RES 300 F 1/10W 0603 | R2_SA;HF_SA;G_SA; | Released | TA-I;RALEC;YAGEO;WALSIN | RM06FTN3000;RTT033000FTP;RC0603FR-07300RL;WR06X3000FTL | Multiple |  | Purchase | SMT | 1 | PCS | R673 |
| 2 | 55.B0710.S12G | 64.33015.6DL | CHIP RES 3.3K F 1/16W 0402 | R2_SA;HF_SA;G_SA; | Released | TAI;RALEC;CYNTEC;YAGEO | RM04FTN3301;RTT023301FTH;RR0510S-332-FN;RC0402FR-073K3L | Multiple |  | Purchase | SMT | 9 | PCS | R339 R343 R346 R348 R349 R353 R356 R364 R434 |
| 2 | 55.B0710.S12G | 64.33R05.6DL | CHIP RES 33 F 1/16W 0402 | R2_SA;HF_SA;G_SA; | Released | TA-I;RALEC;CYNTEC;YAGEO;WALSIN | RM04FTN33R0;RTT0233R0FTH;RR0510S-330-FN;RC0402FR-0733RL;WR04X33R0FTL | Multiple |  | Purchase | SMT | 4 | PCS | R1580 R1581 R1582 R1586 |
| 2 | 55.B0710.S12G | 64.34025.6DL | CHIP RES 34K F 1/16W 0402 | R2_SA;HF_SA;G_SA; | Released | TA-I ; RALEC ; CYNTEC ; YAGEO | RM04FTN3402 ; RTT023402FTH ; RR0510S-3402-FN ; RC0402FR-0734KL | Multiple |  | Purchase | SMT | 1 | PCS | SR774 |
| 2 | 55.B0710.S12G | 64.37415.6DL | CHIP RES 3.74K F 1/16W 0402 | R2_SA;HF_SA;G_SA; | Released | TA-I ; RALEC ; CYNTEC ; YAGEO ; WALSIN | RM04FTN3741;RTT023741FTH;RR0510S-3741-FN;RC0402FR-073K74L;WR04X3741FTL | Multiple |  | Purchase | SMT | 1 | PCS | R2108 |
| 2 | 55.B0710.S12G | 64.39015.6DL | CHIP RES 3.9K F 1/16W 0402 | R2_SA;HF_SA;G_SA; | Released | TA-I;RALEC;CYNTEC;YAGEO;WALSIN | RM04FTN3901;RTT023901FTH;RR0510S-3901-FN;RC0402FR-073K9L;WR04X3901FTL | Multiple |  | Purchase | SMT | 2 | PCS | PR26 PR46 |
| 2 | 55.B0710.S12G | 64.39225.6DL | CHIP RES 39.2K F 1/16W 0402 | R2_SA;HF_SA;G_SA; | Released | TA-I;RALEC;CYNTEC;YAGEO;WALSIN | RM04FTN3922 ; RTT023922FTH ; RR0510S-3922-FN ; RC0402FR-0739K2L;WR04X3922FTL | Multiple |  | Purchase | SMT | 1 | PCS | R2099 |
| 2 | 55.B0710.S12G | 64.3R015.16L | CHIP RES 3.01 F 1/8W 0805 | R2_SA;HF_SA;G_SA; | Released | TA-I;RALEC | RM10FTN3R01;RTT053R01FTP | Multiple |  | Purchase | SMT | 2 | PCS | PR20 PR41 |
| 2 | 55.B0710.S12G | 64.40215.6DL | CHIP RES 4.02K F 1/16W 0402 | R2_SA;HF_SA;G_SA; | Released | TA-I;RALEC;CYNTEC;YAGEO;WALSIN | RM04FTN4021;RTT024021FTH;RR0510S-4021-FN;RC0402FR-074K02L;WR04X4021FTL | Multiple |  | Purchase | SMT | 3 | PCS | PR115 PR167 PR173 |
| 2 | 55.B0710.S12G | 64.42215.6DL | CHIP RES 4.22K F 1/16W 0402 | R2_SA;HF_SA;G_SA; | Released | YAGEO;TA-I;CYNTEC;RALEC | RC0402FR-074K22L;RM04FTN4221;RR0510S-4221-FN;RTT024221FTH | Multiple |  | Purchase | SMT | 1 | PCS | PR122 |
| 2 | 55.B0710.S12G | 64.42225.6DL | CHIP RES 42.2K F 1/16W 0402 | R2_SA;HF_SA;G_SA; | Released | TA-I ; RALEC ; CYNTEC ; YAGEO | RM04FTN4222 ; RTT024222FTH ; RR0510S-4222-FN ; RC0402FR-0742K2L | Multiple |  | Purchase | SMT | 1 | PCS | R9021 |
| 2 | 55.B0710.S12G | 64.44215.6DL | CHIP RES 4.42K F 1/16W 0402(RO | R2_SA;HF_SA;G_SA; | Released | CYNTEC;RALTEC;TAI;WALSIN;YAGEO | RR0510S-4421-FN;RTT024421FTH;RM04FTN4421;WR04X4421FTL;RC0402FR-074K42L | Multiple |  | Purchase | SMT | 1 | PCS | PR79 |
| 2 | 55.B0710.S12G | 64.44225.6DL | CHIP RES 44.2K F 1/16W 0402 | R2_SA;HF_SA;G_SA; | Released | TA-I;RALEC;CYNTEC;YAGEO;WALSIN | RTT024422FTH ; RR0510S-4422-FN ; RM04FTN4422 ; RC0402FR-0744K2L ; WR04X4422FTL | Multiple |  | Purchase | SMT | 1 | PCS | PR33 |
| 2 | 55.B0710.S12G | 64.47015.55L | CHIP RES 4.7K F 1/10W 0603 | R2_SA;HF_SA;G_SA; | Released | TA-I ; RALEC ; YAGEO | RM06FTN4701 ; RTT034701FTP ; RC0603FR-074K7L | Multiple |  | Purchase | SMT | 1 | PCS | R9025 |
| 2 | 55.B0710.S12G | 64.47015.6DL | CHIP RES 4.7K F 1/16W 0402 | R2_SA;HF_SA;G_SA; | Released | TA-I;RALEC;CYNTEC;YAGEO;WALSIN | RM04FTN4701;RTT024701FTH;RR0510S-472-FN;RC0402FR-074K7L;WR04X4701FTL | Multiple |  | Purchase | SMT | 146 | PCS | R160 R161 R163 R166 R167 R173 R174 R177 R178 R186 R195 R196 R2054 R2055 R216 R217 R222 R223 R227 R228 R248 R297 R314 R325 R326 R411 R436 R437 R477 R488 R489 R490 R493 R535 R550 R571 R578 R580 R581 R590 R592 R599 R602 R603 R606 R610 R611 R630 R633 R636 R637 R638 R639 R641 R642 R645 R647 R648 R649 R652 R655 R657 R7896 R7898 R799 R801 R802 R803 R804 SR1274 SR1278 SR1279 SR263 SR266 SR269 SR270 SR271 SR578 SR579 SR589 SR590 SR643 SR645 SR647 SR648 SR654 SR655 SR660 SR670 SR671 SR672 SR673 SR674 SR675 SR676 SR677 SR678 SR679 SR680 SR688 SR719 SR720 SR721 SR725 SR726 SR745 SR746 SR747 SR748 SR749 SR750 SR752 SR753 SR755 SR756 SR758 SR762 SR763 SR766 SR767 SR776 SR777 SR778 SR779 SR780 SR781 SR782 SR783 SR791 SR795 SR839 SR851 SR854 SR857 SR901 SR902 SR908 SR910 SR911 SR912 SR913 SR916 SR917 SR918 SR930 SR932 |
| 2 | 55.B0710.S12G | 64.47025.6DL | CHIP RES 47K F 1/16W 0402 | R2_SA;HF_SA;G_SA; | Released | TA-I;RALEC;CYNTEC;YAGEO;WALSIN | RM04FTN4702;RTT024702FTH;RR0510S-473-FN;RC0402FR-0747KL;WR04X4702FTL | Multiple |  | Purchase | SMT | 1 | PCS | R333 |
| 2 | 55.B0710.S12G | 64.47515.6DL | CHIP RES 4.75K F 1/16W 0402 | R2_SA;HF_SA;G_SA; | Released | TA-I;RALEC;CYNTEC;YAGEO | RM04FTN4751;RTT024751FTH;RR0510S-4751-FN;RC0402FR-074K75L | Multiple |  | Purchase | SMT | 44 | PCS | PR123 PR80 PR87 R383 R384 R390 R391 R392 R393 R394 R459 SR768 SR769 SR770 SR771 SR772 SR773 SR775 SR786 SR787 SR789 SR796 SR797 SR800 SR803 SR804 SR805 SR806 SR808 SR809 SR810 SR811 SR812 SR813 SR816 SR817 SR818 SR819 SR821 SR825 SR826 SR847 SR943 SR944 |
| 2 | 55.B0710.S12G | 64.47535.6DL | CHIP RES 475K F 1/16W 0402 | R2_SA;HF_SA;G_SA; | Released | TA-I;RALEC;CYNTEC;YAGEO | RM04FTN4753;RTT024753FTH;RR0510S-4753-FN;RC0402FR-07475KL | Multiple |  | Purchase | SMT | 3 | PCS | PR160 PR29 PR48 |
| 2 | 55.B0710.S12G | 64.48715.6DL | CHIP RES 4.87K F 1/16W 0402 | R2_SA;HF_SA;G_SA; | Released | TA-I;RALEC;CYNTEC;YAGEO | RM04FTN4871;RTT024871FTH;RR0510S-4871-FN;RC0402FR-074K87L | Multiple |  | Purchase | SMT | 1 | PCS | PR161 |
| 2 | 55.B0710.S12G | 64.49925.6DL | CHIP RES 49.9K F 1/16W 0402 | R2_SA;HF_SA;G_SA; | Released | TA-I ; RALEC ; CYNTEC ; YAGEO ; WALSIN | RM04FTN4992 ; RTT024992FTH ; RR0510S-4992-FN ; RC0402FR-0749K9L ; WR04X4992FTL | Multiple |  | Purchase | SMT | 3 | PCS | R2106 R2107 R337 |
| 2 | 55.B0710.S12G | 64.49R95.16L | CHIP RES 49.9 F 1/8W 0805 | R2_SA;HF_SA;G_SA; | Released | TAI;YAGEO;RALEC | RM10FTN49R9;RC0805FR-0749R9L;RTT0549R9FTP | Multiple |  | Purchase | SMT | 2 | PCS | R397 R398 |
| 2 | 55.B0710.S12G | 64.49R95.6DL | CHIP RES 49.9 F 1/16W 0402 | R2_SA;HF_SA;G_SA; | Released | TA-I;RALEC;CYNTEC;YAGEO;WALSIN | RM04FTN49R9;RTT0249R9FTH;RR0510S-49R9-FN;RC0402FR-0749R9L;WR04X49R9FTL | Multiple |  | Purchase | SMT | 3 | PCS | R401 R402 R7789 |
| 2 | 55.B0710.S12G | 64.49R96.6DL | CHIP RES 49.9 D 1/16W 0402 | R2_SA;HF_SA;G_SA; | Released | YAGEO;WALSIN;TA-I;CYNTEC;RALEC | RC0402DR-0749R9L;WF04H49R9DTL;RM04DTN49R9;RR0510R-49R9-DN;RTT0249R9DTH | Multiple |  | Purchase | SMT | 2 | PCS | R201 R202 |
| 2 | 55.B0710.S12G | 64.51R05.6DL | CHIP RES 51 F 1/16W 0402 | R2_SA;HF_SA;G_SA; | Released | TA-I;RALEC;CYNTEC;YAGEO;WALSIN | RM04FTN51R0;RTT0251R0FTH;RR0510S-510-FN;RC0402FR-0751RL;WR04X51R0FTL | Multiple |  | Purchase | SMT | 3 | PCS | SR582 SR585 SR586 |
| 2 | 55.B0710.S12G | 64.51R05.F9L | CHIP RES 51 F 3/4W 2010 | R2_SA;HF_SA;G_SA; | Released | TA-I ; RALEC ; YAGEO | RM20FEN51R0 ; RTT2051R0FTH ; RC2010FK-0751RL | Multiple |  | Purchase | SMT | 1 | PCS | R479 |
| 2 | 55.B0710.S12G | 64.53615.6DL | CHIP RES 5.36K F 1/16W 0402 | R2_SA;HF_SA;G_SA; | Released | TAI ; RALEC ;CYNTEC ;YAGEO | RM04FTN5361 ;RTT025361FTH ;RR0510S-5361-FN ;RC0402FR-075K36L | Multiple |  | Purchase | SMT | 1 | PCS | PR6888 |
| 2 | 55.B0710.S12G | 64.54925.6DL | CHIP RES 54.9K F 1/16W 0402 | R2_SA;HF_SA;G_SA; | Released | TA-I ; RALEC ; CYNTEC ; YAGEO | RM04FTN5492 ; RTT025492FTH ; RR0510S-5492-FN ; RC0402FR-0754K9L | Multiple |  | Purchase | SMT | 1 | PCS | PR10 |
| 2 | 55.B0710.S12G | 64.56015.6DL | CHIP RES 5.6K F 1/16W 0402(ROH | R2_SA;HF_SA;G_SA; | Released | TA-I;RALEC;CYNTEC;YAGEO;WALSIN | RM04FTN5601;RTT025601FTH;RR0510S-562-FN;RC0402FR-075K6L;WR04X5601FTL | Multiple |  | Purchase | SMT | 1 | PCS | R5764 |
| 2 | 55.B0710.S12G | 64.57625.6DL | CHIP RES 57.6K F 1/16W 0402 | R2_SA;HF_SA;G_SA; | Released | TAI;CYNTEC;YAGEO;RALEC | RM04FTN5762;RR0510S-5762-FN;RC0402FR-0757K6L;RTT025762FTH | Multiple |  | Purchase | SMT | 1 | PCS | R9023 |
| 2 | 55.B0710.S12G | 64.60415.6DL | CHIP RES 6.04K F 1/16W 0402 | R2_SA;HF_SA;G_SA; | Released | TA-I;RALEC;CYNTEC;YAGEO;WALSIN | RM04FTN6041;RTT026041FTH;RR0510S-6041-FN;RC0402FR-076K04L;WR04X6041FTL | Multiple |  | Purchase | SMT | 1 | PCS | R2109 |
| 2 | 55.B0710.S12G | 64.69825.6DL | CHIP RES 69.8K F 1/16W 0402 | R2_SA;HF_SA;G_SA; | Released | TA-I;RALEC;CYNTEC;YAGEO | RM04FTN6982;RTT026982FTH;RR0510S-6982-FN;RC0402FR-0769K8L | Multiple |  | Purchase | SMT | 1 | PCS | PR185 |
| 2 | 55.B0710.S12G | 64.73215.6DL | CHIP RES 7.32K F 1/16W 0402 | R2_SA;HF_SA;G_SA; | Released | TA-I;RALEC;CYNTEC;YAGEO;WALSIN | RM04FTN7321;RTT027321FTH;RR0510S-7321-FN;RC0402FR-077K32L;WR04X7321FTL | Multiple |  | Purchase | SMT | 1 | PCS | PR190 |
| 2 | 55.B0710.S12G | 64.73225.6DL | CHIP RES 73.2K F 1/16W 0402 | R2_SA;HF_SA;G_SA; | Released | TA-I;RALEC;CYNTEC;YAGEO;WALSIN | RM04FTN7322;RTT027322FTH;RR0510S-7322-FN;RC0402FR-0773K2L;WR04X7322FTL | Multiple |  | Purchase | SMT | 2 | PCS | PR31 PR51 |
| 2 | 55.B0710.S12G | 64.86625.6DL | CHIP RES 86.6K F 1/16W 0402 | R2_SA;HF_SA;G_SA; | Released | TA-I;RALEC;CYNTEC;YAGEO | RM04FTN8662;RTT028662FTH;RR0510S-8662-FN;RC0402FR-0786K6L | Multiple |  | Purchase | SMT | 1 | PCS | R9022 |
| 2 | 55.B0710.S12G | 64.95315.6DL | CHIP RES 9.53K F 1/16W 0402 | R2_SA;HF_SA;G_SA; | Released | TA-I;RALEC;CYNTEC;YAGEO | RM04FTN9531;RTT029531FTH;RR0510S-9531-FN;RC0402FR-079K53L | Multiple |  | Purchase | SMT | 1 | PCS | R9014 |
| 2 | 55.B0710.S12G | 64.R0025.L1L | CHIP RES 0.002 F 1W 0612 | R2_SA; | Released | CYNTEC | RL1632L4-R002-FN | Single |  | Purchase | SMT | 1 | PCS | R9020 |
| 2 | 55.B0710.S12G | 64.R0085.97L | CHIP RES 0.008 F 2W 2512 | R2_SA;HF_SA;G_SA; | Released | CYNTEC;TAI;YAGEO | RL-3264-9-R008-FN;RLM25FEER008;PF2512FKF7W0R008L | Multiple |  | Purchase | SMT | 1 | PCS | R520 |
| 2 | 55.B0710.S12G | 64.R5105.55L | CHIP RES 0.51 F 1/10W 0603 L/F | R2_SA;HF_SA;G_SA; | Released | RALEC ; TA-I ; YAGEO ; WALSIN | RTT03R510FTP ; RL06FTNR510 ; RL0603FR-070R51L ; WW06XR510FTL | Multiple |  | Purchase | SMT | 9 | PCS | SR715 SR716 SR827 SR831 SR832 SR833 SR834 SR835 SR836 |
| 2 | 55.B0710.S12G | 68.00084.771 | CHIP BEAD BLM41PG600SN1L MURAT | R2_SA; | Released | MURATA | BLM41PG600SN1L | Single |  | Purchase | SMT | 2 | PCS | PL10 PL8 |
| 2 | 55.B0710.S12G | 68.00084.831 | CHIP BEAD BLM21PG220SN1D (LF) | R2_SA;HF_SA; | Released | MURATA | BLM21PG220SN1D | Single |  | Purchase | SMT | 2 | PCS | PL2 PL4 |
| 2 | 55.B0710.S12G | 68.00084.A61 | CHIP BEAD BLM21PG300SN1D MURAT | R2_SA; | Released | MURATA | BLM21PG300SN1D | Single |  | Purchase | SMT | 1 | PCS | L7 |
| 2 | 55.B0710.S12G | 68.00109.171 | CHIP BEAD MMZ2012S601ATA1N TDK | R2_SA; | Released | TDK | MMZ2012S601ATA1N | Single |  | Purchase | SMT | 3 | PCS | L4 L5 L6 |
| 2 | 55.B0710.S12G | 68.00224.051 | CHIP BEAD MPZ2012S300AT TDK | R2_SA; | Released | TDK | MPZ2012S300AT | Single |  | Purchase | SMT | 8 | PCS | SL11 SL15 SL16 SL17 SL18 SL19 SL20 SL8 |
| 2 | 55.B0710.S12G | 68.00224.201 | CHIP BEAD MPZ2012S601AT TDK | R2_SA;HF_SA; | Released | TDK | MPZ2012S601AT | Single |  | Purchase | SMT | 11 | PCS | SL12 SL13 SL14 SL2 SL21 SL22 SL3 SL4 SL5 SL6 SL7 |
| 2 | 55.B0710.S12G | 68.00395.001 | CHIP BEAD 0181 28F0181-1SR-10 | R2_SA; | Released | LAIRD | 28F0181-1SR-10 | Single |  | Purchase | SMT | 1 | PCS | SL9 |
| 2 | 55.B0710.S12G | 68.2R21B.10J | CHIP IND 2.2UH MMD-06CZ-2R2M-V | R2_SA;HF_SA;G_SA; | Released | MAGLAYER | MMD-06CZ-2R2M-V1W | Single |  | Purchase | SMT | 1 | PCS | PL5 |
| 2 | 55.B0710.S12G | 68.3012N.10C | CHIP IND 300NH FP1007R3-R30-R | R2_SA; | Released | COOPER | FP1007R3-R30-R | Single |  | Purchase | SMT | 1 | PCS | PL9 |
| 2 | 55.B0710.S12G | 68.3R310.20V | CHIP CHOKE 3.3UH PCMB063T-3R3MS | R2_SA;HF_SA; | Released | CYNTEC | PCMB063T-3R3MS | Single |  | Purchase | SMT | 1 | PCS | PL12 |
| 2 | 55.B0710.S12G | 68.3R31A.20D | CHIP CHOKE 3.3UH M PCMB065T-3R3MS | R2_SA; | Released | CYNTEC | PCMB065T-3R3MS | Single |  | Purchase | SMT | 1 | PCS | PL3 |
| 2 | 55.B0710.S12G | 68.6R810.20P | CHIP CHOKE 6.8UH PCMB063T-6R8MS | R2_SA;HF_SA; | Released | CYNTEC | PCMB063T-6R8MS | Single |  | Purchase | SMT | 1 | PCS | PL1 |
| 2 | 55.B0710.S12G | 68.R4710.10M | CHIP CHOKE 0.47UH PCMC063T-R47 | R2_SA;HF_SA;G_SA; | Released | CYNTEC | PCMC063T-R47MN | Single |  | Purchase | SMT | 1 | PCS | PL11 |
| 2 | 55.B0710.S12G | 71.00551.00A | IC CLK BUF ICS551MLFT SOIC 8P | R2_SA; | Released | IDT | ICS551MLFT | Single |  | Purchase | SMT | 1 | PCS | U21 |
| 2 | 55.B0710.S12G | 71.01250.A0U | IC BMC AST1250A1-GP TFBGA 408P | R2_SA; | Released | ASPEED | AST1250A1-GP | Single |  | Purchase | SMT | 1 | PCS | U40 |
| 2 | 55.B0710.S12G | 71.02514.F03 | IC USB HUB USB2514B-AEZC-TR QFN 36P | R2_SA;HF_SA; | Released | SMSC | USB2514B-AEZC-TR | Single |  | Purchase | SMT | 1 | PCS | U183 |
| 2 | 55.B0710.S12G | 71.08563.A0A | IC RTC/CALENDAR PCF8563T SO8 | R2_SA;G_SA; | Released | NXP | PCF8563T/F4 | Single |  | Purchase | SMT | 1 | PCS | U43 |
| 2 | 55.B0710.S12G | 71.09306.00I | IC I2C BUS PCA9306DCTT SSOP 8P | R2_SA; | Released | TI | PCA9306DCTT | Multiple |  | Purchase | SMT | 7 | PCS | SU52 SU62 SU65 SU66 SU68 SU74 SU78 |
| 2 | 55.B0710.S12G | 71.09550.00W | IC LED DRV PCA9550DP TSSOP 8P | R2_SA; | Released | NXP | PCA9550DP | Single |  | Purchase | SMT | 1 | PCS | U12 |
| 2 | 55.B0710.S12G | 71.09552.00W | IC IC2 LED DRV PCA9552PW TSSOP | R_SA; | Released | NXP | PCA9552 | Single |  | Purchase | SMT | 1 | PCS | U188 |
| 2 | 55.B0710.S12G | 71.09575.00W | IC I2C BUS PCA9575PW2 TSSOP 28P | R2_SA; | Released | NXP | PCA9575PW2 | Single |  | Purchase | SMT | 1 | PCS | SU14 |
| 2 | 55.B0710.S12G | 71.P9511.00W | IC BUF PCA9511ADP-T TSSOP 8P | R2_SA; | Released | NXP | PCA9511ADP-T | Single |  | Purchase | SMT | 2 | PCS | U23 U24 |
| 2 | 55.B0710.S12G | 72.02464.A01 | IC EEPRM 24LC64-I/SN SO8 | R2_SA; | Released | MICROCHIP | 24LC64-I/SN | Single |  | Purchase | SMT | 1 | PCS | U16 |
| 2 | 55.B0710.S12G | 72.24C64.G01 | IC EEPROM AT24C64D-SSHM-T SOIC 8P | R2_SA;HF_SA; | Released | ATMEL | AT24C64D-SSHM-T | Single |  | Purchase | SMT | 2 | PCS | SU61 SU67 |
| 2 | 55.B0710.S12G | 72.29128.Z09 | IC FEROM S29GL128S10TFIV20 TSOP 56P | R2_SA; | Released | SPANSION | S29GL128S10TFIV20 | Single |  | Purchase | SMT | 2 | PCS | SU58 SU73 |
| 2 | 55.B0710.S12G | 72.56416.P0U | IC SDRAM NT5CB64M16FP-DH FBGA 96BALLS | R2_SA;HF_SA;G_SA; | Released | NANYA | NT5CB64M16FP-DH | Single |  | Purchase | SMT | 1 | PCS | U18 |
| 2 | 55.B0710.S12G | 73.00102.007 | IC TRANSLATOR TXS0102DCUR VSSOP 8P | R2_SA;HF_SA; | Released | TI | TXS0102DCUR | Single |  | Purchase | SMT | 3 | PCS | U184 U185 U186 |
| 2 | 55.B0710.S12G | 73.01G00.BHH | IC CMOS SN74LVC1G00DCKR DCK 5P | R2_SA;HF_SA;G_SA; | Released | TI | SN74LVC1G00DCKR | Single |  | Purchase | SMT | 1 | PCS | U44 |
| 2 | 55.B0710.S12G | 73.01G07.01H | IC BUF SN74LVC1G07DCKRG4 DCK5P | R2_SA; | Released | TI | SN74LVC1G07DCKRG4 | Single |  | Purchase | SMT | 1 | PCS | U32 |
| 2 | 55.B0710.S12G | 73.01G07.CHH | IC CMOS 74LVC1G07DCKR SC70-5 | R2_SA;HF_SA;G_SA; | Released | TI | SN74LVC1G07DCKR | Single |  | Purchase | SMT | 1 | PCS | U25 |
| 2 | 55.B0710.S12G | 73.01G08.L03 | IC CMOS SN74LVC1G08DCKR SC-70 | R2_SA;HF_SA;G_SA; | Released | TI | SN74LVC1G08DCKR | Single |  | Purchase | SMT | 9 | PCS | SU79 SU80 U172 U173 U177 U38 U39 U46 U50 |
| 2 | 55.B0710.S12G | 73.01G11.AHH | IC CMOS SN74LVC1G11DCKR DCK | R_SA;G_SA; | Released | TI | SN74LVC1G11DCKR | Single |  | Purchase | SMT | 1 | PCS | U45 |
| 2 | 55.B0710.S12G | 73.01G17.BHH | IC CMOS SN74LVC1G17DCKR DCK 5P | R2_SA;HF_SA; | Released | TI | SN74LVC1G17DCKR | Single |  | Purchase | SMT | 1 | PCS | PU99 |
| 2 | 55.B0710.S12G | 73.03861.G0C | IC BUS SW PI3C3861-AQE QSOP 24P | R2_SA; | Released | PERICOM | PI3C3861-AQE | Single |  | Purchase | SMT | 4 | PCS | SU13 SU15 SU16 SU18 |
| 2 | 55.B0710.S12G | 73.07414.FHB | IC CMOS 74LVC14APW TSSOP 14P | R2_SA; | Released | NXP | 74LVC14APW | Single |  | Purchase | SMT | 1 | PCS | U175 |
| 2 | 55.B0710.S12G | 73.1G126.DHG | IC CMOS SN74LVC1G126DCKR SC70 | R2_SA;HF_SA; | Released | TI | SN74LVC1G126DCKR | Single |  | Purchase | SMT | 4 | PCS | U171 U174 U178 U179 |
| 2 | 55.B0710.S12G | 73.2G07D.020 | IC BUF/DRV SN74LVC2G07DBVR SOT23-6 | R2_SA;HF_SA; | Released | TI | SN74LVC2G07DBVR | Single |  | Purchase | SMT | 1 | PCS | SU76 |
| 2 | 55.B0710.S12G | 73.2G125.0AB | IC DUAL-BUFFER/LIN 74HC2G125DP TSSOP8 | R2_SA; | Released | NXP | 74HC2G125DP | Single |  | Purchase | SMT | 2 | PCS | U192 U193 |
| 2 | 55.B0710.S12G | 73.74774.003 | IC BUS SN74AVC4T774RGYR QFN16P | R2_SA;HF_SA; | Released | TI | SN74AVC4T774RGYR | Single |  | Purchase | SMT | 1 | PCS | U181 |
| 2 | 55.B0710.S12G | 73.8T245.B29 | IC XCVR SN74LVC8T245DGVR TVSOP | R2_SA; | Released | TI | SN74LVC8T245DGVR | Single |  | Purchase | SMT | 4 | PCS | SU69 SU70 SU71 SU72 |
| 2 | 55.B0710.S12G | 74.00075.B79 | IC TEMP SENSOR TMP75AIDGKR MSOP 8P | R2_SA; | Released | TI | TMP75AIDGKR | Single |  | Purchase | SMT | 3 | PCS | U134 U135 U136 |
| 2 | 55.B0710.S12G | 74.00235.033 | IC S.R VT235WFQX-ADJ QFN 19P | R_C; | Released | VOLTERRA | VT235WFQX-ADJ | Single |  | Purchase | SMT | 1 | PCS | PU13 |
| 2 | 55.B0710.S12G | 74.00393.I21 | IC V.C LM393ADR SOIC 8P(ROHS) | R2_SA;HF_SA; | Released | TI | LM393ADR | Single |  | Purchase | SMT | 2 | PCS | U36 U41 |
| 2 | 55.B0710.S12G | 74.01178.079 | IC MONI ADM1178-2ARMZ-R7 MSOP | R2_SA; | Released | ADI | ADM1178-2ARMZ-R7 | Single |  | Purchase | SMT | 1 | PCS | U34 |
| 2 | 55.B0710.S12G | 74.02065.07F | IC PWR SW TPS2065DBVT SOT-23 5P | R2_SA;HF_SA; | Released | TI | TPS2065DBVT | Single |  | Purchase | SMT | 1 | PCS | U194 |
| 2 | 55.B0710.S12G | 74.03808.073 | IC RESET TPS3808G18DRVR QFN 6P | R2_SA; | Released | TI | TPS3808G18DRVR | Single |  | Purchase | SMT | 2 | PCS | SU57 SU75 |
| 2 | 55.B0710.S12G | 74.04214.079 | IC TEMP SEN TMP421AIDCNRG4 SOT23 8P | R2_SA; | Released | TI | TMP421AIDCNRG4 | Single |  | Purchase | SMT | 1 | PCS | U15 |
| 2 | 55.B0710.S12G | 74.23157.A99 | IC A.S TS5A23157DGSR DGS 10P | R2_SA;G_SA; | Released | TI | TS5A23157DGSR | Single |  | Purchase | SMT | 3 | PCS | U26 U27 U28 |
| 2 | 55.B0710.S12G | 74.53312.073 | IC PWM CTRL TPS53312RGTR QFN 16P | R2_SA; | Released | TI | TPS53312RGTR | Single |  | Purchase | SMT | 2 | PCS | PU1 PU100 |
| 2 | 55.B0710.S12G | 74.53318.073 | IC PWR CTRL TPS53318DQPR QFN 22P | R2_SA;HF_SA; | Released | TI | TPS53318DQPR | Single |  | Purchase | SMT | 2 | PCS | PU2 PU3 |
| 2 | 55.B0710.S12G | 74.53355.073 | IC PWM CTRL TPS53355DQPR QFN 22P | R2_SA; | Released | TI | TPS53355DQPR | Single |  | Purchase | SMT | 1 | PCS | PU12 |
| 2 | 55.B0710.S12G | 74.74801.A33 | IC LDO TPS74801RGW QFN 20P | R2_SA; | Released | TI | TPS74801RGW | Single |  | Purchase | SMT | 3 | PCS | PU10 PU5 PU6 |
| 2 | 55.B0710.S12G | 75.00054.E7D | IC DIODE S.B BAT54C-7-F SOT-23 3P | R2_SA;HF_SA;G_SA; | Released | DIODES | BAT54C-7-F | Single |  | Purchase | SMT | 1 | PCS | D13 |
| 2 | 55.B0710.S12G | 78.10134.1FL | CHIP CAP C 100P 50V J0402 NPO | R2_SA;HF_SA;G_SA; | Released | AVX;DARFON;MURATA;PHYCOMP;SAMSUNG;TAIYO;TDK;WALSIN;YAGEO | CM05CG101J50AH;C1005NP0101JGT;GRM1555C1H101JA01D;223886915101;CL05C101JB5NNNC;UMK105CH101JV-F;C1005C0G1H101JT;0402N101J500LT;CC0402JRNPO9BN101 | Multiple |  | Purchase | SMT | 3 | PCS | C193 C196 C203 |
| 2 | 55.B0710.S12G | 78.10224.2FL | CHIP CAP C 1000P 50V K0402 X7R | R2_SA;HF_SA;G_SA; | Released | AVX;DARFON;MURATA;PHYCOMP;SAMSUNG;TAIYO;TDK;MURATA;AVX;YAGEO | CM05X7R102K50AH;C1005X7R102KGT;GRM155R71H102KA01D;223858715623;CL05B102KB5NNNC;UMK105BJ102KV-F;C1005X7R1H102KT000F;WBM155R71H102KA01D;04025C102KAT2A;CC0402KRX7R9BB102 | Multiple |  | Purchase | SMT | 33 | PCS | C220 C221 C239 PC189 PC221 PC31 PC51 SC1009 SC1010 SC1011 SC1012 SC1013 SC1014 SC1015 SC1016 SC1029 SC1030 SC1031 SC1032 SC1033 SC1034 SC1035 SC1036 SC1211 SC1212 SC1213 SC1214 SC1215 SC1216 SC1217 SC1218 SC1219 SC1220 |
| 2 | 55.B0710.S12G | 78.10321.2FL | CHIP CAP C 0.01U 16V K0402 X7R | R2_SA;HF_SA;G_SA; | Released | AVX;DARFON;MURATA;PHYCOMP;SAMSUNG;TAIYO;TDK;WALSIN;MURATA;YAGEO | 0402YC103KAT2A;C1005X7R103KET;GRM155R71C103KA01D;223878715636;CL05B103KO5NNNC;EMK105BJ103KV-F;C1005X7R1C103KT000F;0402B103K160CT;WBM155R71C103KA01D;CC0402KRX7R7BB103 | Multiple |  | Purchase | SMT | 4 | PCS | C222 C224 C7273 SC877 |
| 2 | 55.B0710.S12G | 78.10322.2FL | CHIP CAP C 0.01U 25V K0402 X7R | R2_SA;HF_SA;G_SA; | Released | AVX;DARFON;MURATA;PHYCOMP;SAMSUNG;TAIYO;TDK;MURATA;YAGEO | 04023C103KAT2A;C1005X7R103KFT;GRM155R71E103KA01D;223891715636;CL05B103KA5NNNC;TMK105BJ103KV-F;C1005X7R1E103KT000F;WBM155R71E103KA01D;CC0402KRX7R8BB103 | Multiple |  | Purchase | SMT | 2 | PCS | C177 C179 |
| 2 | 55.B0710.S12G | 78.10323.20L | CHIP CAP C 0.01U 10V K0201 X7R | R2_SA;HF_SA;G_SA; | Released | MURATA;PHYCOMP;YAGEO;DARFON | GRM033R71A103KA01D;223824815636;CC0201KRX7R6BB103;C0603X7R103KDT | Multiple |  | Purchase | SMT | 64 | PCS | SC1067 SC1068 SC1069 SC1070 SC1071 SC1072 SC1073 SC1074 SC1075 SC1076 SC1077 SC1078 SC1079 SC1080 SC1081 SC1082 SC1083 SC1084 SC1085 SC1086 SC1087 SC1088 SC1089 SC1090 SC1091 SC1092 SC1093 SC1094 SC1095 SC1096 SC1097 SC1102 SC1103 SC1104 SC1105 SC1261 SC1262 SC1263 SC1264 SC1265 SC1266 SC1267 SC1268 SC1269 SC1270 SC1271 SC1272 SC1273 SC878 SC879 SC880 SC881 SC882 SC883 SC884 SC885 SC890 SC891 SC892 SC893 SC894 SC895 SC901 SC902 |
| 2 | 55.B0710.S12G | 78.10324.2BL | CHIP CAP C 0.01U 50V K0603 X7R | R2_SA;HF_SA;G_SA; | Released | AVX;KEMET;MURATA;PHYCOMP;SAMSUNG;TDK;DARFON;PANASONIC;WALSIN | 06035C103KAT2A;C0603C103K5RAC;GRM188R71H103KA01D;223858615636;CL10B103KB8NNNC;C1608X7R1H103KT;C1608X7R103KGT;ECJ1VB1H103K;0603B103K500CT | Multiple |  | Purchase | SMT | 3 | PCS | PC210 PC211 PC218 |
| 2 | 55.B0710.S12G | 78.10324.2FL | CHIP CAP C 0.01U 50V K0402 X7R | R2_SA;HF_SA;G_SA; | Released | MURATA;PHYCOMP;DARFON;TDK;SAMSUNG;WALSIN;MURATA | GRM155R71H103KA88D;223858715636;C1005X7R103KGT;C1005X7R1H103KT;CL05B103KB5NNNC;0402B103K500CT;WBM155R71H103KA01D | Multiple |  | Purchase | SMT | 21 | PCS | C129 C130 C131 C132 C133 C134 C135 C136 C143 C242 C244 SC1065 SC1109 SC1274 SC1275 SC1276 SC1277 SC1278 SC1279 SC1280 SC1281 |
| 2 | 55.B0710.S12G | 78.10420.50L | CHIP CAP C 0.1U 6.3V K0201 X5R | R2_SA;HF_SA;G_SA; | Released | MURATA;AVX;DARFON;WALSIN;MATSUKI;TAIYO ;SAMSUNG | GRM033R60J104KE19D;02016D104KAT2A;C0603X5R104KCT;0201X104K6R3CT;MAG01X5R0J104K;RMJMK063BJ104KP-F;CL03A104KQ3NNNC | Multiple |  | Purchase | SMT | 99 | PCS | SC1134 SC1135 SC1136 SC1137 SC1138 SC1139 SC1140 SC1141 SC1142 SC1143 SC1144 SC1145 SC1149 SC1153 SC1157 SC1161 SC1162 SC1163 SC1167 SC1168 SC1169 SC1179 SC1180 SC1181 SC1185 SC1186 SC1187 SC1191 SC1192 SC1193 SC1197 SC1201 SC1221 SC1222 SC1223 SC1224 SC1225 SC1226 SC1227 SC1228 SC1229 SC1230 SC1231 SC1232 SC1233 SC1234 SC1235 SC1236 SC1237 SC1238 SC1239 SC1240 SC1241 SC1242 SC1243 SC1244 SC1245 SC1246 SC1247 SC1248 SC1249 SC1250 SC1251 SC1252 SC1253 SC1254 SC1255 SC1256 SC1257 SC1258 SC1259 SC1260 SC918 SC922 SC926 SC930 SC934 SC938 SC939 SC940 SC942 SC943 SC944 SC948 SC949 SC950 SC951 SC952 SC953 SC954 SC955 SC959 SC960 SC961 SC962 SC963 SC964 SC965 SC966 |
| 2 | 55.B0710.S12G | 78.10421.2BL | CHIP CAP C 0.1U 16V K0603 X7R | R2_SA;HF_SA;G_SA; | Released | AVX;DARFON;MURATA;PHYCOMP;SAMSUNG;TAIYO;TDK;WALSIN | 0603YC104KAT2A;C1608X7R104KET;GRM188R71C104KA01D;223878615649;CL10B104KO8NNNC;EMK107BJ104KA-T;C1608X7R1C104KT;0603B104K160CT | Multiple |  | Purchase | SMT | 2 | PCS | PC35 PC55 |
| 2 | 55.B0710.S12G | 78.10421.2FL | CHIP CAP C 0.1U 16V K0402 X7R | R2_SA;HF_SA;G_SA; | Released | DARFON;MURATA;PHYCOMP;SAMSUNG;TAIYO;TDK;WALSIN;YAGEO | C1005X7R104KET;GRM155R71C104KA88D;223878715649;CL05B104KO5NNNC;EMK105BJ104KV-FR ;C1005X7R1C104KT000F;0402B104K160CT;CC0402KRX7R7BB104 | Multiple |  | Purchase | SMT | 196 | PCS | C142 C146 C151 C171 C172 C173 C174 C175 C176 C178 C181 C182 C183 C184 C185 C186 C187 C195 C202 C223 C225 C228 C229 C230 C231 C236 C241 C243 C249 C263 C264 C269 C272 C3 C319 C322 C323 C324 C325 C326 C327 C328 C333 C4 C41 C42 C43 C5 C7272 C7788 C81 C82 C83 C84 C85 C86 C87 C88 C89 C90 PC102 PC138 PC148 PC186 PC225 PC234 PC78 PC88 PC90 SC1000 SC1001 SC1002 SC1003 SC1004 SC1005 SC1006 SC1007 SC1008 SC1037 SC1038 SC1039 SC1040 SC1041 SC1042 SC1043 SC1044 SC1045 SC1046 SC1047 SC1048 SC1049 SC1050 SC1051 SC1052 SC1053 SC1054 SC1055 SC1056 SC1057 SC1058 SC1059 SC1060 SC1061 SC1062 SC1063 SC1064 SC1066 SC1098 SC1099 SC1100 SC1101 SC1106 SC1107 SC1108 SC1110 SC1111 SC1112 SC1113 SC1114 SC1115 SC1116 SC1117 SC1118 SC1119 SC1120 SC1121 SC1122 SC1123 SC1173 SC1174 SC1175 SC1282 SC1283 SC1284 SC1285 SC1286 SC1287 SC1290 SC1291 SC1292 SC1293 SC1294 SC1295 SC1297 SC1298 SC1299 SC1300 SC1301 SC1303 SC1306 SC1307 SC1311 SC307 SC308 SC427 SC428 SC429 SC431 SC433 SC435 SC436 SC545 SC546 SC547 SC564 SC634 SC860 SC867 SC914 SC973 SC974 SC975 SC976 SC977 SC978 SC979 SC980 SC981 SC982 SC983 SC984 SC985 SC986 SC987 SC988 SC989 SC990 SC991 SC992 SC993 SC994 SC995 SC996 SC997 SC998 SC999 |
| 2 | 55.B0710.S12G | 78.10422.2BL | CHIP CAP C 0.1U 25V K0603 X7R | R2_SA;HF_SA;G_SA; | Released | AVX;DARFON;MURATA;PHYCOMP;SAMSUNG;TAIYO;TDK;WALSIN;YAGEO | 06033C104KAT2A;C1608X7R104KFT;GRM188R71E104KA01D;223891615649;CL10B104KA8NNNC;TMK107BJ104KA-T;C1608X7R1E104KT;0603B104K250CT;CC0603KRX7R8BB104 | Multiple |  | Purchase | SMT | 7 | PCS | C267 C274 C312 C7274 PC25 PC45 PC6 |
| 2 | 55.B0710.S12G | 78.10422.2FL | CHIP CAP C 0.1U 25V K0402 X7R | R2_SA;HF_SA;G_SA; | Released | YAGEO;WALSIN;MURATA;TDK | CC0402KRX7R8BB104;0402B104K250CT;GRM155R71E104KE14D;C1005X7R1E104KT | Multiple |  | Purchase | SMT | 41 | PCS | C256 C259 C261 C262 C271 C275 C277 C279 C280 C282 C283 C285 C286 C288 C289 C290 C291 C292 C293 C294 C295 C297 C298 C301 C303 C309 C310 C329 C330 C331 C340 C8081 C8083 C8084 C8085 C8086 C8087 C8088 C8089 PC30 PC50 |
| 2 | 55.B0710.S12G | 78.10423.2FL | CHIP CAP C 0.1U 10V K0402 X7R | R2_SA;HF_SA;G_SA; | Released | MURATA;PHYCOMP;SAMSUNG;TAIYO;TDK;DARFON;WALSIN;MURATA;YAGEO | GRM155R71A104KA01D;223824715649;CL05B104KP5NNNC;RMLMK105BJ104KV-F;C1005X7R1A104KT000F;C1005X7R104KDT;0402B104K100CT;WBM155R71A104KA01D;CC0402KRX7R6BB104 | Multiple |  | Purchase | SMT | 3 | PCS | PC146 PC86 PC99 |
| 2 | 55.B0710.S12G | 78.10424.2BL | CHIP CAP C 0.1U 50V K0603 X7R | R2_SA;HF_SA;G_SA; | Released | MURATA;TDK;AVX;PHYCOMP;SAMSUNG;DARFON;MATSUKI;WALSIN | GRM188R71H104KA93D;C1608X7R1H104KT000N;06035C104KAT2A;223858615649;CL10B104KB8NNNC;C1608X7R104KGT;MAG03X7R1H104K;0603B104K500CT | Multiple |  | Purchase | SMT | 9 | PCS | PC10 PC172 PC185 PC195 PC219 PC223 PC229 PC27 PC47 |
| 2 | 55.B0710.S12G | 78.10431.2FL | CHIP CAP 0.1UF J 16V 0402 X7R | R2_SA;HF_SA;G_SA; | Released | KEMET;TDK;MURATA;PHYCOMP;DARFON;SAMSUNG;WALSIN | C0402C104J4RAC;C1005X7R1C104JT;GRM155R71C104JA88D;223878715549;C1005X7R104JET;CL05B104JO5NNNC;0402B104J160CT | Multiple |  | Purchase | SMT | 4 | PCS | C152 C238 C240 C332 |
| 2 | 55.B0710.S12G | 78.10432.2BL | CHIP CAP C 0.1U 25V J0603 X7R | R2_SA;HF_SA;G_SA; | Released | PHYCOMP;WALSIN;DARFON | 223891615549;0603B104J250CT;C1608X7R104JFT | Multiple |  | Purchase | SMT | 3 | PCS | C7278 C7316 C7317 |
| 2 | 55.B0710.S12G | 78.10510.5SL | CHIP CAP C 1U 6.3V M0201 X5R | R2_SA;HF_SA;G_SA; | Released | MURATA;DARFON;TAIYO;SAMSUNG;AVX | GRM033R60J105MEA2D;C0603X5R105MCT;JDK063BJ105MP-FD;CL03A105MQ3CSNH;CV03X5R105M06AH | Multiple |  | Purchase | SMT | 20 | PCS | SC1133 SC1148 SC1152 SC1156 SC1160 SC1166 SC1178 SC1184 SC1190 SC1196 SC1200 SC917 SC921 SC925 SC929 SC933 SC937 SC941 SC947 SC958 |
| 2 | 55.B0710.S12G | 78.10520.2BL | CHIP CAP C 1U 6.3V K0603 X7R | R2_SA;HF_SA;G_SA; | Released | MURATA;TAIYO;DARFON;WALSIN;PHYCOMP;SAMSUNG | GRM188R70J105K;JMK107B7105KA-T;C1608X7R105KCT;0603B105K6R3CT;225520615663;CL10B105KQ8NNNC | Multiple |  | Purchase | SMT | 10 | PCS | C192 C194 C201 C210 C232 C233 C255 C317 C370 C371 |
| 2 | 55.B0710.S12G | 78.10521.2BL | CHIP CAP C 1U 16V K0603 X7R | R2_SA;HF_SA;G_SA; | Released | KEMET;MURATA;TAIYO;TDK;PHYCOMP;WALSIN;SAMSUNG;DARFON | C0603C105K4RAC;GRM188R71C105KA12D;EMK107B7105KA-T;C1608X7R1C105KT;223878615663;0603B105K160CT;CL10B105KO8NNNC;C1608X7R105KET | Multiple |  | Purchase | SMT | 8 | PCS | C180 C316 C7275 C7276 C7277 PC13 PC224 PC232 |
| 2 | 55.B0710.S12G | 78.10521.5BL | CHIP CAP C 1U 16V K0603 X5R | R2_SA;HF_SA;G_SA; | Released | AVX;DARFON;MURATA;PHYCOMP;SAMSUNG;TAIYO;TDK;WALSIN;YAGEO | CM105X5R105K16AT;C1608X5R105KET;GRM188R61C105KA93D;223878613663;CL10A105KO8NNNC;EMK107BJ105KA-T;C1608X5R1C105KT;0603X105K160CT;CC0603KRX5R7BB105 | Multiple |  | Purchase | SMT | 1 | PCS | PC190 |
| 2 | 55.B0710.S12G | 78.10522.2BL | CHIP CAP C 1U 25V K0603 X7R | R2_SA;HF_SA;G_SA; | Released | MURATA;TAIYO;TDK;WALSIN;SAMSUNG;DARFON | GRM188R71E105KA12D;TMK107BJ105KA-T;C1608X7R1E105KT;CL10B105KA8NNNC;C1608X7R105KFT | Multiple |  | Purchase | SMT | 16 | PCS | C253 C258 C278 C281 C284 C287 C299 C302 C311 PC207 PC208 PC209 PC212 PC213 PC215 PC5 |
| 2 | 55.B0710.S12G | 78.10522.5BL | CHIP CAP C 1U 25V K0603 X5R | R2_SA;HF_SA;G_SA; | Released | MURATA;TDK;PHYCOMP;TAIYO;MATSUKI;DARFON;TDK;WALSIN;SAMSUNG;YAGEO | GRM188R61E105KA12D;C1608X5R1E105KT000N;223891613663;TMK107BJ105KA-T;MAG03X5R1E105K;C1608X5R105KFT;C1608X5R1E105KT000N;0603X105K250CT;CL10A105KA8NNNC;CC0603KRX5R8BB105 | Multiple |  | Purchase | SMT | 1 | PCS | PC1083 |
| 2 | 55.B0710.S12G | 78.10523.2BL | CHIP CAP C 1U 10V K0603 X7R | R2_SA;HF_SA;G_SA; | Released | MURATA;TAIYO;TDK;WALSIN;SAMSUNG;DARFON | GRM188R71A105KA61D;LMK107B7105KA;C1608X7R1A105KT;0603B105K100CT;CL10B105KP8NNNC;C1608X7R105KDT | Multiple |  | Purchase | SMT | 20 | PCS | C197 C198 C199 C200 C204 C207 C219 C304 C305 C334 C335 C336 C337 C338 PC29 PC49 SC426 SC430 SC432 SC434 |
| 2 | 55.B0710.S12G | 78.10523.5FL | CHIP CAP C 1U 10V K0402 X5R | R2_SA;HF_SA;G_SA; | Released | MURATA;TDK;DARFON;MATSUKI;PHYCOMP;TAIYO;SAMSUNG;WALSIN | GRM155R61A105KE15D;C1005X5R1A105KT;C1005X5R105KDT;MAG02X5R1A105K;223824713663;LMK105BJ105KVF;CL05A105KP5NNNC;0402X105K100CT | Multiple |  | Purchase | SMT | 11 | PCS | C205 C206 C208 C212 C213 C214 C215 C216 C217 C218 PC20 |
| 2 | 55.B0710.S12G | 78.10523.8FL | CHIP CAP C 1U 10V K 0402 X6S | R2_SA;HF_SA; | Released | TAIYO;MURATA;TDK;SAMSUNG | LMK105C6105KV-F;GRM155C81A105KA12D;C1005X6S1A105KT;CL05X105KP5NNNC | Multiple |  | Purchase | SMT | 24 | PCS | C145 C155 C158 C159 C162 C163 C166 C167 C254 C320 SC1023 SC1024 SC1025 SC1026 SC1027 SC1028 SC1172 SC1289 SC967 SC968 SC969 SC970 SC971 SC972 |
| 2 | 55.B0710.S12G | 78.10524.5BL | CHIP CAP C 1U 50V K0603 X5R | R2_SA;HF_SA;G_SA; | Released | MURATA;TAIYO;DARFON;SAMSUNG;PHYCOMP;TDK | GRM188R61H105KAALD;UMK316BJ105KL-T;C1608X5R105KGT;CL10A105KB8NNNC;223858613663;CC0603KRX5R9BB105;C1608X5R1H105KT | Multiple |  | Purchase | SMT | 1 | PCS | PC193 |
| 2 | 55.B0710.S12G | 78.10620.21L | CHIP CAP C 10U 6.3V K0805 X7R | R2_SA;HF_SA;G_SA; | Released | MURATA;TAIYO;DARFON;AVX KYOCERA | GRM21BR70J106K;JMK212B7106KG-T;C2012X7R106KC; CM21X7R106K06AT | Multiple |  | Purchase | SMT | 28 | PCS | C170 SC1017 SC1018 SC1019 SC1020 SC1021 SC1022 SC1147 SC1151 SC1155 SC1195 SC1199 SC1202 SC1203 SC1204 SC1205 SC1206 SC1207 SC1208 SC1209 SC1210 SC1288 SC916 SC920 SC924 SC928 SC932 SC936 |
| 2 | 55.B0710.S12G | 78.10620.51L | CHIP CAP C 10UF 6.3V K0805 X5R | R2_SA;HF_SA;G_SA; | Released | MURATA;AVX;TDK;TAIOY;PHYCOMP;DARFON;SAMSUNG;MATSUK | GRM21BR60J106KE19L ; CM21X5R106K06AT ; C2012X5R0J106KT000N; JMK212BJ106KG-T ; 225020013676 ; C2012X5R106KCT ; CL21A106KQFNNNE ;MAG05X5R0J106K | Multiple |  | Purchase | SMT | 19 | PCS | C227 PC139 PC140 PC142 PC143 PC144 PC145 PC79 PC80 PC82 PC83 PC84 PC85 PC91 PC92 PC94 PC95 PC96 PC97 |
| 2 | 55.B0710.S12G | 78.10622.52L | CHIP CAP C 10U 25V K1206 X5R | R2_SA;HF_SA;G_SA; | Released | TAIYO;MURATA;AVX;TDK;KEMET;MATSUKI;PHYCOMP;DARFON;SAMSUNG | TMK316BJ106KL-T;GRM31CR61E106KA12L;12063D106KAT2A;C3216X5R1E106KT;C1206C106K3PAC;MAG06X5R1E106K;222291113676;C3216X5R106KFP;CL31A106KAHNNNE | Multiple |  | Purchase | SMT | 3 | PCS | PC204 PC205 PC206 |
| 2 | 55.B0710.S12G | 78.10710.52L | CHIP CAP C 100U 6.3V M1206 X5R | R2_SA;HF_SA;G_SA; | Released | MURATA;TAIYO | GRM31CR60J107ME39L;JMK316BJ107ML | Multiple |  | Purchase | SMT | 7 | PCS | PC37 PC38 PC39 PC40 PC57 PC58 PC59 |
| 2 | 55.B0710.S12G | 78.10710.53L | CHIP CAP C 100U 6.3V M1210 X5R | R2_SA;HF_SA;G_SA; | Released | MURATA;TAIYO;TDK;KEMET;TAIYO;SAMSUNG | GRM32ER60J107ME20L;JMK325BJ107MM-T;C3225X5R0J107MT000N;C1210C107M9PAC;JMK325ABJ107MM-P;CL32A107MQVNNNE | Multiple |  | Purchase | SMT | 11 | PCS | SC1131 SC1132 SC1158 SC1164 SC1170 SC1176 SC1182 SC1188 SC945 SC956 SC957 |
| 2 | 55.B0710.S12G | 78.12034.1FL | CHIP CAP C 12P 50V J0402 NPO | R2_SA;HF_SA;G_SA; | Released | AVX;MURATA;PHYCOM;TAIYO;TDK;DARFON;MURATA;WALSIN | 04025A120JAT2A;GRM1555C1H120JZ01D;223886915129;UMK105CH120JW-F;C1005C0G1H120J;C1005NP0120JGT;GRM1555C1H120JA01D;0402N120J500 | Multiple |  | Purchase | SMT | 4 | PCS | SC1124 SC1125 SC886 SC887 |
| 2 | 55.B0710.S12G | 78.15322.2FL | CHIP CAP C 0.015U 25V K0402 X7R | R2_SA;HF_SA;G_SA; | Released | MURATA;TDK;WALSIN;DARFON;PHYCOMP | GRM155R71E153KA61D;C1005X7R1E153KT000F;0402B153K250CT;C1005X7R153KFT;223891715638 | Multiple |  | Purchase | SMT | 1 | PCS | C372 |
| 2 | 55.B0710.S12G | 78.18034.1BL | CHIP CAP 18P50V J0603 NPO(ROHS | R2_SA;HF_SA;G_SA; | Released | MURATA;PHYCOMP;TDK;TAIYO;SAMSUNG;DARFON;AVX;WALSIN | GRM1885C1H180JA01D;223886715189;C1608C0G1H180JT;UMK107CG180JZ-T;CL10C180JB8NNNC;C1608NPO180JGT;06035A180JAT2A;0603N180J500LT | Multiple |  | Purchase | SMT | 2 | PCS | C8090 C8091 |
| 2 | 55.B0710.S12G | 78.22124.2FL | CHIP CAP C 220P 50V K0402 X7R | R2_SA;HF_SA;G_SA; | Released | MURATA;AVX;TAIYO;PHYCOMN;DARFON | GRM155R71H221KA01D;04025C221KAT2A;UMK105BJ221KV-F;223858715614;C1005X7R221KGT | Multiple |  | Purchase | SMT | 3 | PCS | C209 C211 PC217 |
| 2 | 55.B0710.S12G | 78.22224.2FL | CHIP CAP C 2200P 50V K0402 X7R | R2_SA;HF_SA;G_SA; | Released | MURATA;AVX;TDK;TAIYO;PHYCOMN;DARFON;SAMSUNG;WALSIN;YAGEO | GRM155R71H222KA01D;04025C222KAT2A;C1005X7R1H222KT000F;UMK105BJ222KV-F;223858715627;C1005X7R222KGT;CL05B222KB5NNNC;0402B222K500CT;CC0402KRX7R9BB222 | Multiple |  | Purchase | SMT | 1 | PCS | C266 |
| 2 | 55.B0710.S12G | 78.22410.5SL | CHIP CAP C 0.22U 6.3V M0201 X5R | R2_SA;HF_SA;G_SA; | Released | MURATA ; DARFON ; SAMSUNG ; TAIYO ; MURATA | GRM033R60J224ME15D ; C0603X5R224MCT ; CL03A224MQ3NNNH ;JMK063BJ224MP-F ; GRM033R60J223KE | Multiple |  | Purchase | SMT | 16 | PCS | SC1296 SC861 SC862 SC863 SC864 SC865 SC866 SC868 SC869 SC870 SC871 SC872 SC873 SC874 SC875 SC876 |
| 2 | 55.B0710.S12G | 78.22523.5BL | CHIP CAP C 2.2U 10V K 0603 X5R | R2_SA;HF_SA;G_SA; | Released | MURATA;TAIYO;SAMSUNG;TDK;PHYCOMP;PANASONIC;DARFON;WALSIN | GRM188R61A225KD;LMK107BJ225KA-T;CL10A225KP8NNNC;C1608X5R1A225KT000N;223824613667;ECJ1VB1A225K;C1608X5R225KDT;0603X225K100CT | Multiple |  | Purchase | SMT | 2 | PCS | BC1 BC2 |
| 2 | 55.B0710.S12G | 78.22610.51L | CHIP CAP C 22U 6.3V M0805 X5R | R2_SA;HF_SA;G_SA; | Released | MURATA;TAIYO;TDK;KEMET;PANASONIC;MATSUKI;SAMSUNG;DARFON;WALSIN;YAGEO;AVX | GRM21BR60J226ME39L;JMK212BJ226MG-T;C2012X5R0J226MT;C0805C226M9PAC;ECJ2FB0J226M;MAG05X5R0J226M;CL21A226MQQNNNE;C2012X5R226MCP;0805X226M6R3CT;CC0805MKX5R5BB226;CV21X5R226M06AT | Multiple |  | Purchase | SMT | 22 | PCS | C1698 C339 PC235 PC236 SC1146 SC1150 SC1154 SC1159 SC1165 SC1171 SC1177 SC1183 SC1189 SC1194 SC1198 SC915 SC919 SC923 SC927 SC931 SC935 SC946 |
| 2 | 55.B0710.S12G | 78.22610.5BL | CHIP CAP C 22U 6.3V M0603 X5R | R2_SA;HF_SA;G_SA; | Released | MURATA;TDK;SAMSUNG;TAIYO;DARFON | GRM188R60J226MEA0D;C1608X5R0J226MT;CL10A226MQ8NRNC;JDK107BBJ226MA-T;C1608X5R226MCT | Multiple |  | Purchase | SMT | 6 | PCS | PC176 PC177 PC178 PC179 PC36 PC56 |
| 2 | 55.B0710.S12G | 78.22612.51L | CHIP CAP C 22U 25V M0805 X5R | R2_SA;HF_SA;G_SA; | Released | MURATA;SANSUNG;DARFON;TDK | GRM21BR61E226ME44L;CL21A226MAQNNNE;C2012X5R226MFP;C2012X5R1E226MT | Multiple |  | Purchase | SMT | 25 | PCS | C257 C270 C276 C296 C300 C308 PC169 PC170 PC171 PC173 PC174 PC175 PC21 PC216 PC22 PC226 PC227 PC23 PC24 PC41 PC42 PC43 PC44 PC7 PC8 |
| 2 | 55.B0710.S12G | 78.22613.51L | CHIP CAP C 22U 10V M0805 X5R | R2_SA;HF_SA;G_SA; | Released | SAMSUNG;PHYCOMP;MURATA;TAIYO;TDK;SAMSUNG;DARFON | CL21A226MPQNNNG;222224013781;GRM21BR61A226ME51L;LMK212BJ226MG-T;C2012X5R1A226MT;CL21A226MPCLRNC;C2012X5R226MDP | Multiple |  | Purchase | SMT | 2 | PCS | PC15 PC16 |
| 2 | 55.B0710.S12G | 78.22620.22L | CHIP CAP C 22U 6.3V K 1206 X7R | R2_SA;HF_SA;G_SA; | Released | YAGEO;MURATA;KYOCERA;SAMSUNG | CC1206KKX7R5BB226;GRM31CR70J226KE19L;CM316X7R226K06AT;CL31B226KQHNNNE | Multiple |  | Purchase | SMT | 8 | PCS | PC196 PC197 PC198 PC199 PC200 PC201 PC202 PC203 |
| 2 | 55.B0710.S12G | 78.33224.2FL | CHIP CAP C 3300P 50V K0402 X7R | R2_SA;HF_SA;G_SA; | Released | MURATA;AVX;TDK;TAIYO;PHYCOMN;DARFON | GRM155R71H332KA01D;04025C332KAT2A;C1005X7R1H332KT000F;UMK105BJ332KV-F;223858715629;C1005X7R332KGT | Multiple |  | Purchase | SMT | 2 | PCS | PC11 PC230 |
| 2 | 55.B0710.S12G | 78.33324.2BL | CHIP CAP 0.033U 50V K0603 X7R | R2_SA;HF_SA;G_SA; | Released | MURATA;AVX;PHYCOMP;DARFON | GRM188R71H333KA61D;06035C333KAT2A;223858615643;C1608X7R333KGT | Multiple |  | Purchase | SMT | 1 | PCS | C7279 |
| 2 | 55.B0710.S12G | 78.33420.5FL | CHIP CAP C 0.33U 6.3V K0402 X5 | R2_SA;HF_SA;G_SA; | Released | MURATA;TDK | GRM155R60J334KE01D;C1005X5R0J334KT000F | Multiple |  | Purchase | SMT | 1 | PCS | PC222 |
| 2 | 55.B0710.S12G | 78.47124.2FL | CHIP CAP C 470P50V K0402 X7R | R2_SA;HF_SA;G_SA; | Released | AVX;DARFON;MURATA;PHYCOMP;TAIYO;TDK;SAMSUNG;WALSIN;YAGEO | 04025C471KAT2A;C1005X7R471KGT;GRM155R71H471KA01D;223858715618;UMK105BJ471KV-F;C1005X7R1H471KT000F;CL05B471KB5NNNC;0402B471K500CT;CC0402KRX7R9BB471 | Multiple |  | Purchase | SMT | 3 | PCS | PC100 PC147 PC87 |
| 2 | 55.B0710.S12G | 78.47321.2FL | CHIP CAP C 0.047U 16V K0402 X7 | R2_SA;HF_SA;G_SA; | Released | MURATA;PHYCOMP;TAIYO;TDK;WALSIN;DARFON;SAMSUNG;YAGEO | GRM155R71C473KA01D;223878715645;EMK105BJ473KV-F;C1005X7R1C473KT000F;0402B473K160CT;C1005X7R473KET;CL05B473KO5NNNC;CC0402KRX7R7BB473 | Multiple |  | Purchase | SMT | 1 | PCS | C265 |
| 2 | 55.B0710.S12G | 78.47422.2BL | CHIP CAP C 0.47U 25V K0603 X7R | R2_SA;HF_SA;G_SA; | Released | MURATA;SAMSUNG;DARFON | GRM188R71E474KA12D;CL10B474KA8NNNC;C1608X7R474KFT | Multiple |  | Purchase | SMT | 3 | PCS | PC137 PC191 PC192 |
| 2 | 55.B0710.S12G | 78.47610.51L | CHIP CAP C 47U 6.3V M0805 X5R | R2_SA;HF_SA;G_SA; | Released | TAIYO;SAMSUNG;MURATA;TDK | JMK212BJ476MG-T;CL21A476MQYNNNE;GRM21BR60J476ME15;C2012X5R0J476MT00HE | Multiple |  | Purchase | SMT | 6 | PCS | PC180 PC181 PC182 PC183 PC237 PC238 |
| 2 | 55.B0710.S12G | 78.47611.53L | CHIP CAP C 47U 16V M1210 X5R | R2_SA;HF_SA;G_SA; | Released | MURATA;TAIYO;TAIYO | GRM32ER61C476ME15L;EMK325BJ476MM-T;EMK325BJ476MM-P | Multiple |  | Purchase | SMT | 5 | PCS | TC10 TC11 TC12 TC13 TC14 |
| 2 | 55.B0710.S12G | 78.47613.52L | CHIP CAP C 47U 10V M1206 X5R | R2_SA;HF_SA;G_SA; | Released | MURATA;TAIYO;WALSIN;SAMSUNG;PHYCOMP | GRM31CR61A476ME15L ; LMK316BJ476ML-T ; 1206X476M100CT;CL31A476MPHNNNE;225024113785 | Multiple |  | Purchase | SMT | 2 | PCS | PC17 PC18 |
| 2 | 55.B0710.S12G | 78.68224.2BL | CHIP CAP 6800P 50V K0603 X7R | R2_SA;HF_SA;G_SA; | Released | WALSIN;AVX;DARFON;MURATA;PHYCOMP;TDK | 0603B682K500CT;06035C682KAT2A;C1608X7R682KGT;GRM188R71H682KA01D;223858615634;C1608X7R1H682KT000N | Multiple |  | Purchase | SMT | 2 | PCS | PC194 PC214 |
| 2 | 55.B0710.S12G | 79.47719.2BL | CHIP CAP 470UF 2V EEFSX0D471X | R2_SA;HF_SA;G_SA; | Released | PANASONIC | EEFSX0D471XE | Single |  | Purchase | SMT | 4 | PCS | PTC4 PTC5 PTC6 PTC7 |
| 2 | 55.B0710.S12G | 82.20013.291 | OSC 48MHZ 50PPM 15PF 3.3V HSO321S SMD | R2_SA; | Released | HARMONY | SSW048000I3CH | Single |  | Purchase | SMT | 1 | PCS | OSC1 |
| 2 | 55.B0710.S12G | 82.20043.111 | OSC 50MHZ 50PPM DSO751SV SMD | R2_SA; | Released | KDS | 1XSH050000AVK | Single |  | Purchase | SMT | 1 | PCS | X1 |
| 2 | 55.B0710.S12G | 82.30001.931 | XTAL 32.768KHZ 8P20PPM DST310S | R2_SA; | Released | KDS | 1TJF080DP1A000A | Single |  | Purchase | SMT | 1 | PCS | X2 |
| 2 | 55.B0710.S12G | 82.30004.901 | XTAL 24MHZ 12PF20PPM HCX-3SB SMD | R2_SA;HF_SA; | Released | HOSONIC | E3SB24.0000F12M22 | Single |  | Purchase | SMT | 1 | PCS | X11 |
| 2 | 55.B0710.S12G | 82.30020.891 | XTAL 25MHZ 12P30PPM HSX531S | R2_SA; | Released | HARMONY | X1H025000FC1H | Single |  | Purchase | SMT | 2 | PCS | SX1 SX2 |
| 2 | 55.B0710.S12G | 83.01221.I70 | LED BLUE 12-21/BHC-YLMRY-2C | R2_SA;HF_SA; | Released | EVERLIGHT | 12-21/BHC-YLMRY/2C | Single |  | Purchase | SMT | 1 | PCS | LED5 |
| 2 | 55.B0710.S12G | 83.01521.H70 | LED RED 15-21-SURC-S530-A3-TR8 | R2_SA; | Released | EVERLIGHT | 15-21-SURC-S530-A3-TR8 | Single |  | Purchase | SMT | 1 | PCS | LED6 |
| 2 | 55.B0710.S12G | 83.01921.C70 | LED 1.6*0.8 YEL 19-21UYOC/S530 | R2_SA;HF_SA;G_SA; | Released | EVERLIGHT | 19-21UYOC/S530-A2TR8 | Single |  | Purchase | SMT | 2 | PCS | LED14 LED15 |
| 2 | 55.B0710.S12G | 83.01921.S70 | LED Y/G 19-21/G6C-BM2P1B/3T SM | R2_SA;HF_SA;G_SA; | Released | EVERLIGHT | 19-21/G6C-BM2P1B/3T | Single |  | Purchase | SMT | 4 | PCS | SLED25 SLED26 SLED27 SLED28 |
| 2 | 55.B0710.S12G | 83.1221R.070 | LED RED ET 12-21/R6C-AP1Q2L/2C SMD | R2_SA; | Released | EVERLIGHT | 12-21/R6C-AP1Q2L/2C | Single |  | Purchase | SMT | 1 | PCS | LED4 |
| 2 | 55.B0710.S12G | 83.SMF15.0AH | DIODE TVS SMF15A SOD-123FL | R2_SA; | Released | PANJIT | SMF15A | Single |  | Purchase | SMT | 1 | PCS | D37 |
| 2 | 55.B0710.S12G | 84.00359.C31 | FET MOS FDN359BN NC SUPERSOT23 | R2_SA; | Released | FAIRCHILD | FDN359BN | Single |  | Purchase | SMT | 2 | PCS | PQ3 Q78 |
| 2 | 55.B0710.S12G | 84.00925.03N | FET MOS PH0925CL NC LFPAK | R2_SA; | Released | NXP | PH0925CL | Single |  | Purchase | SMT | 2 | PCS | Q23 Q76 |
| 2 | 55.B0710.S12G | 84.03400.B37 | FET MOS AO3400A NC SOT-23 3P | R2_SA;HF_SA;G_SA; | Released | AOS | AO3400A | Single |  | Purchase | SMT | 3 | PCS | SQ1 SQ2 SQ5 |
| 2 | 55.B0710.S12G | 84.03904.L06 | XTOR PMBS3904 NPN SOT23 (GP) | R2_SA;HF_SA;G_SA; | Released | NXP | PMBS3904 | Single |  | Purchase | SMT | 2 | PCS | Q22 Q5 |
| 2 | 55.B0710.S12G | 84.04406.B37 | FET MOS AO4406AL NC SO-8(HF) | R2_SA;HF_SA;G_SA; | Released | AOS | AO4406AL | Single |  | Purchase | SMT | 1 | PCS | PQ1 |
| 2 | 55.B0710.S12G | 84.27002.C3F | FET MOS 2N7002DW-7-F NC SOT363 | R2_SA;HF_SA; | Released | DIODES | 2N7002DW-7-F | Single |  | Purchase | SMT | 3 | PCS | PU9 Q10 SU63 |
| 2 | 55.B0710.S12G | 84.2N702.E31 | FET MOS 2N7002A-7 NC SOT-23 ESD 1.2KV | R2_SA;HF_SA;G_SA; | Released | DIODES | 2N7002A-7 | Single |  | Purchase | SMT | 32 | PCS | PQ4 PQ5 PQ6 PQ7 Q11 Q12 Q13 Q14 Q15 Q16 Q17 Q19 Q20 Q21 Q6 Q7 Q8 Q9 Q92 Q93 Q94 Q97 SQ11 SQ12 SQ13 SQ14 SQ15 SQ16 SQ17 SQ18 SQ3 SQ4 |
| 2 | 55.B0710.S12G | 84.M3904.01K | XTOR MMBT3904TT1G NPN SOT-416 | R2_SA; | Released | ON | MMBT3904TT1G | Single |  | Purchase | SMT | 2 | PCS | Q77 Q80 |
| 2 | 55.B0710.S12G | 84.N3904.011 | XTOR NST3904F3T5G NPN SOT-1123 | R2_SA; | Released | ON | NST3904F3T5G | Single |  | Purchase | SMT | 1 | PCS | PQ33 |
| 1 | 55.B0710.D12G | 60.B0711.001 | ASSY PANTHER DUIDE RIGHT HB | R2_C; | Released | TBD |  | Single | E | Purchase | DIP | 1 | PCS |  |
| 1 | 55.B0710.D12G | 60.B0712.001 | ASSY PANTHER DUIDE LEFT HB | R2_C; | Released | TBD |  | Single | E | Purchase | DIP | 1 | PCS |  |
| 1 | 55.B0710.D12G | 60.B0725.001 | ASSY BASE BOARD RIGHT HANDLE HB PVT | R2_C; | Released | TBD |  | Single | E | Purchase | DIP | 1 | PCS |  |
| 1 | 55.B0710.D12G | 60.B0726.001 | ASSY BASE BOARD LEFT HANDLE HB PVT | R2_C; | Released | TBD |  | Single | E | Purchase | DIP | 1 | PCS |  |
| 1 | 55.B0710.D12G | 60.B0727.001 | ASSY BASE BOARD MYLAR HB PVT | R2_C; | Released | TBD |  | Single | E | Purchase | DIP | 1 | PCS |  |
| 1 | 55.B0710.D12G | 72.25635.A01 | IC FEROM MX25L25635FMI-10G SOP 16P | R2_SA; | Released | MXIC | MX25L25635FMI-10G | Single |  | Purchase | DIP | 1 | PCS | U19 |
| 1 | 55.B0710.D12G | 86.00T32.544 | SCRW WAFRE M3.0 L4 NYLOK | R2_SA; | Released | TBD |  | Single |  | Purchase | DIP | 8 | PCS |  |
| 1 | 55.B0710.D12G | 86.0A233.5R0 | SCRW PH FM +N 2.5x5-B | R2_SA; | Released | TBD |  | Single |  | Purchase | DIP | 2 | PCS |  |
| 1 | 55.B0710.D12G | 86.1A522.5R0 | SCREW M2-5 | R2_SA;G_SA; | Released | TBD | TBD | Single |  | Purchase | DIP | 4 | PCS |  |
| 1 | 55.B0710.D12G | 86.5A534.5R0 | SCRW FLAT M3 *5 | R2_SA;HF_SA; | Released | WEN HAOU |  | Single |  | Purchase | DIP | 5 | PCS |  |
